FILE_TYPE = MACRO_DRAWING;
SET COLOR_WIRE YELLOW;
SET COLOR_PROP ORANGE;
SET COLOR_DOT WHITE;
SET COLOR_ARC YELLOW;
SET COLOR_BODY GREEN;
SET COLOR_NOTE PURPLE;
SET PROP_DISPLAY VALUE;
SET PAGE_NUMBER P40;
FORCEADD GENOA_SP5..4
(-4600 3650);
FORCEPROP 1 LAST LOCATION U26
J 0
(-5245 6481);
DISPLAY 0.489362 (-5245 6481);
PAINT SKYBLUE (-5245 6481);
FORCEPROP 0 LAST $SEC 4
J 0
(-5225 6525);
DISPLAY 0.680851 (-5225 6525);
PAINT MONO (-5225 6525);
DISPLAY INVISIBLE (-5225 6525);
FORCEPROP 0 LAST CDS_SEC 4
J 0
(-5250 6475);
DISPLAY 1.021277 (-5250 6475);
DISPLAY INVISIBLE (-5250 6475);
FORCEPROP 0 LASTPIN (-5400 3025) $PN BC60
J 2
(-5410 3035);
DISPLAY 0.489362 (-5410 3035);
PAINT MONO (-5410 3035);
FORCEPROP 0 LASTPIN (-5400 2975) $PN BD60
J 2
(-5410 2985);
DISPLAY 0.489362 (-5410 2985);
PAINT MONO (-5410 2985);
FORCEPROP 0 LASTPIN (-5400 1875) $PN BF60
J 2
(-5410 1885);
DISPLAY 0.489362 (-5410 1885);
PAINT MONO (-5410 1885);
FORCEPROP 0 LASTPIN (-5400 1825) $PN BG60
J 2
(-5410 1835);
DISPLAY 0.489362 (-5410 1835);
PAINT MONO (-5410 1835);
FORCEPROP 0 LASTPIN (-5400 2175) $PN AT58
J 2
(-5410 2185);
DISPLAY 0.489362 (-5410 2185);
PAINT MONO (-5410 2185);
FORCEPROP 0 LASTPIN (-5400 2075) $PN AU59
J 2
(-5410 2085);
DISPLAY 0.489362 (-5410 2085);
PAINT MONO (-5410 2085);
FORCEPROP 0 LASTPIN (-5400 2875) $PN AV60
J 2
(-5410 2885);
DISPLAY 0.489362 (-5410 2885);
PAINT MONO (-5410 2885);
FORCEPROP 0 LASTPIN (-5400 2825) $PN AW59
J 2
(-5410 2835);
DISPLAY 0.489362 (-5410 2835);
PAINT MONO (-5410 2835);
FORCEPROP 0 LASTPIN (-5400 2725) $PN BN59
J 2
(-5410 2735);
DISPLAY 0.489362 (-5410 2735);
PAINT MONO (-5410 2735);
FORCEPROP 0 LASTPIN (-5400 1725) $PN AU60
J 2
(-5410 1735);
DISPLAY 0.489362 (-5410 1735);
PAINT MONO (-5410 1735);
FORCEPROP 0 LASTPIN (-5400 1675) $PN AV58
J 2
(-5410 1685);
DISPLAY 0.489362 (-5410 1685);
PAINT MONO (-5410 1685);
FORCEPROP 0 LASTPIN (-5400 1575) $PN BP58
J 2
(-5410 1585);
DISPLAY 0.489362 (-5410 1585);
PAINT MONO (-5410 1585);
FORCEPROP 0 LASTPIN (-5400 3875) $PN AW60
J 2
(-5410 3885);
DISPLAY 0.489362 (-5410 3885);
PAINT MONO (-5410 3885);
FORCEPROP 0 LASTPIN (-5400 3825) $PN AY60
J 2
(-5410 3835);
DISPLAY 0.489362 (-5410 3835);
PAINT MONO (-5410 3835);
FORCEPROP 0 LASTPIN (-5400 3775) $PN AY58
J 2
(-5410 3785);
DISPLAY 0.489362 (-5410 3785);
PAINT MONO (-5410 3785);
FORCEPROP 0 LASTPIN (-5400 3725) $PN BA59
J 2
(-5410 3735);
DISPLAY 0.489362 (-5410 3735);
PAINT MONO (-5410 3735);
FORCEPROP 0 LASTPIN (-5400 3675) $PN BA60
J 2
(-5410 3685);
DISPLAY 0.489362 (-5410 3685);
PAINT MONO (-5410 3685);
FORCEPROP 0 LASTPIN (-5400 3625) $PN BB60
J 2
(-5410 3635);
DISPLAY 0.489362 (-5410 3635);
PAINT MONO (-5410 3635);
FORCEPROP 0 LASTPIN (-5400 3575) $PN BB58
J 2
(-5410 3585);
DISPLAY 0.489362 (-5410 3585);
PAINT MONO (-5410 3585);
FORCEPROP 0 LASTPIN (-3800 2425) $PN AJ60
J 0
(-3790 2435);
DISPLAY 0.489362 (-3790 2435);
PAINT MONO (-3790 2435);
FORCEPROP 0 LASTPIN (-3800 2375) $PN AK58
J 0
(-3790 2385);
DISPLAY 0.489362 (-3790 2385);
PAINT MONO (-3790 2385);
FORCEPROP 0 LASTPIN (-3800 2325) $PN AK60
J 0
(-3790 2335);
DISPLAY 0.489362 (-3790 2335);
PAINT MONO (-3790 2335);
FORCEPROP 0 LASTPIN (-3800 2275) $PN AL59
J 0
(-3790 2285);
DISPLAY 0.489362 (-3790 2285);
PAINT MONO (-3790 2285);
FORCEPROP 0 LASTPIN (-3800 2225) $PN AN60
J 0
(-3790 2235);
DISPLAY 0.489362 (-3790 2235);
PAINT MONO (-3790 2235);
FORCEPROP 0 LASTPIN (-3800 2175) $PN AP58
J 0
(-3790 2185);
DISPLAY 0.489362 (-3790 2185);
PAINT MONO (-3790 2185);
FORCEPROP 0 LASTPIN (-3800 2125) $PN AP60
J 0
(-3790 2135);
DISPLAY 0.489362 (-3790 2135);
PAINT MONO (-3790 2135);
FORCEPROP 0 LASTPIN (-3800 2075) $PN AR59
J 0
(-3790 2085);
DISPLAY 0.489362 (-3790 2085);
PAINT MONO (-3790 2085);
FORCEPROP 0 LASTPIN (-3800 6025) $PN E60
J 0
(-3790 6035);
DISPLAY 0.489362 (-3790 6035);
PAINT MONO (-3790 6035);
FORCEPROP 0 LASTPIN (-3800 5975) $PN F58
J 0
(-3790 5985);
DISPLAY 0.489362 (-3790 5985);
PAINT MONO (-3790 5985);
FORCEPROP 0 LASTPIN (-3800 5925) $PN F60
J 0
(-3790 5935);
DISPLAY 0.489362 (-3790 5935);
PAINT MONO (-3790 5935);
FORCEPROP 0 LASTPIN (-3800 5875) $PN G59
J 0
(-3790 5885);
DISPLAY 0.489362 (-3790 5885);
PAINT MONO (-3790 5885);
FORCEPROP 0 LASTPIN (-3800 5825) $PN J60
J 0
(-3790 5835);
DISPLAY 0.489362 (-3790 5835);
PAINT MONO (-3790 5835);
FORCEPROP 0 LASTPIN (-3800 5775) $PN K58
J 0
(-3790 5785);
DISPLAY 0.489362 (-3790 5785);
PAINT MONO (-3790 5785);
FORCEPROP 0 LASTPIN (-3800 5725) $PN K60
J 0
(-3790 5735);
DISPLAY 0.489362 (-3790 5735);
PAINT MONO (-3790 5735);
FORCEPROP 0 LASTPIN (-3800 5675) $PN L59
J 0
(-3790 5685);
DISPLAY 0.489362 (-3790 5685);
PAINT MONO (-3790 5685);
FORCEPROP 0 LASTPIN (-3800 5575) $PN L60
J 0
(-3790 5585);
DISPLAY 0.489362 (-3790 5585);
PAINT MONO (-3790 5585);
FORCEPROP 0 LASTPIN (-3800 5525) $PN M58
J 0
(-3790 5535);
DISPLAY 0.489362 (-3790 5535);
PAINT MONO (-3790 5535);
FORCEPROP 0 LASTPIN (-3800 5475) $PN M60
J 0
(-3790 5485);
DISPLAY 0.489362 (-3790 5485);
PAINT MONO (-3790 5485);
FORCEPROP 0 LASTPIN (-3800 5425) $PN N59
J 0
(-3790 5435);
DISPLAY 0.489362 (-3790 5435);
PAINT MONO (-3790 5435);
FORCEPROP 0 LASTPIN (-3800 5375) $PN R60
J 0
(-3790 5385);
DISPLAY 0.489362 (-3790 5385);
PAINT MONO (-3790 5385);
FORCEPROP 0 LASTPIN (-3800 5325) $PN T58
J 0
(-3790 5335);
DISPLAY 0.489362 (-3790 5335);
PAINT MONO (-3790 5335);
FORCEPROP 0 LASTPIN (-3800 5275) $PN T60
J 0
(-3790 5285);
DISPLAY 0.489362 (-3790 5285);
PAINT MONO (-3790 5285);
FORCEPROP 0 LASTPIN (-3800 5225) $PN U59
J 0
(-3790 5235);
DISPLAY 0.489362 (-3790 5235);
PAINT MONO (-3790 5235);
FORCEPROP 0 LASTPIN (-3800 5125) $PN U60
J 0
(-3790 5135);
DISPLAY 0.489362 (-3790 5135);
PAINT MONO (-3790 5135);
FORCEPROP 0 LASTPIN (-3800 5075) $PN V58
J 0
(-3790 5085);
DISPLAY 0.489362 (-3790 5085);
PAINT MONO (-3790 5085);
FORCEPROP 0 LASTPIN (-3800 5025) $PN V60
J 0
(-3790 5035);
DISPLAY 0.489362 (-3790 5035);
PAINT MONO (-3790 5035);
FORCEPROP 0 LASTPIN (-3800 4975) $PN W59
J 0
(-3790 4985);
DISPLAY 0.489362 (-3790 4985);
PAINT MONO (-3790 4985);
FORCEPROP 0 LASTPIN (-3800 4925) $PN AA60
J 0
(-3790 4935);
DISPLAY 0.489362 (-3790 4935);
PAINT MONO (-3790 4935);
FORCEPROP 0 LASTPIN (-3800 4875) $PN AB58
J 0
(-3790 4885);
DISPLAY 0.489362 (-3790 4885);
PAINT MONO (-3790 4885);
FORCEPROP 0 LASTPIN (-3800 4825) $PN AB60
J 0
(-3790 4835);
DISPLAY 0.489362 (-3790 4835);
PAINT MONO (-3790 4835);
FORCEPROP 0 LASTPIN (-3800 4775) $PN AC59
J 0
(-3790 4785);
DISPLAY 0.489362 (-3790 4785);
PAINT MONO (-3790 4785);
FORCEPROP 0 LASTPIN (-3800 4675) $PN AC60
J 0
(-3790 4685);
DISPLAY 0.489362 (-3790 4685);
PAINT MONO (-3790 4685);
FORCEPROP 0 LASTPIN (-3800 4625) $PN AD58
J 0
(-3790 4635);
DISPLAY 0.489362 (-3790 4635);
PAINT MONO (-3790 4635);
FORCEPROP 0 LASTPIN (-3800 4575) $PN AD60
J 0
(-3790 4585);
DISPLAY 0.489362 (-3790 4585);
PAINT MONO (-3790 4585);
FORCEPROP 0 LASTPIN (-3800 4525) $PN AE59
J 0
(-3790 4535);
DISPLAY 0.489362 (-3790 4535);
PAINT MONO (-3790 4535);
FORCEPROP 0 LASTPIN (-3800 4475) $PN AG60
J 0
(-3790 4485);
DISPLAY 0.489362 (-3790 4485);
PAINT MONO (-3790 4485);
FORCEPROP 0 LASTPIN (-3800 4425) $PN AH58
J 0
(-3790 4435);
DISPLAY 0.489362 (-3790 4435);
PAINT MONO (-3790 4435);
FORCEPROP 0 LASTPIN (-3800 4375) $PN AH60
J 0
(-3790 4385);
DISPLAY 0.489362 (-3790 4385);
PAINT MONO (-3790 4385);
FORCEPROP 0 LASTPIN (-3800 4325) $PN AJ59
J 0
(-3790 4335);
DISPLAY 0.489362 (-3790 4335);
PAINT MONO (-3790 4335);
FORCEPROP 0 LASTPIN (-5400 6025) $PN G60
J 2
(-5410 6035);
DISPLAY 0.489362 (-5410 6035);
PAINT MONO (-5410 6035);
FORCEPROP 0 LASTPIN (-5400 5925) $PN N60
J 2
(-5410 5935);
DISPLAY 0.489362 (-5410 5935);
PAINT MONO (-5410 5935);
FORCEPROP 0 LASTPIN (-5400 5825) $PN W60
J 2
(-5410 5835);
DISPLAY 0.489362 (-5410 5835);
PAINT MONO (-5410 5835);
FORCEPROP 0 LASTPIN (-5400 5725) $PN AE60
J 2
(-5410 5735);
DISPLAY 0.489362 (-5410 5735);
PAINT MONO (-5410 5735);
FORCEPROP 0 LASTPIN (-5400 5625) $PN AL60
J 2
(-5410 5635);
DISPLAY 0.489362 (-5410 5635);
PAINT MONO (-5410 5635);
FORCEPROP 0 LASTPIN (-5400 5525) $PN J59
J 2
(-5410 5535);
DISPLAY 0.489362 (-5410 5535);
PAINT MONO (-5410 5535);
FORCEPROP 0 LASTPIN (-5400 5425) $PN R59
J 2
(-5410 5435);
DISPLAY 0.489362 (-5410 5435);
PAINT MONO (-5410 5435);
FORCEPROP 0 LASTPIN (-5400 5325) $PN AA59
J 2
(-5410 5335);
DISPLAY 0.489362 (-5410 5335);
PAINT MONO (-5410 5335);
FORCEPROP 0 LASTPIN (-5400 5225) $PN AG59
J 2
(-5410 5235);
DISPLAY 0.489362 (-5410 5235);
PAINT MONO (-5410 5235);
FORCEPROP 0 LASTPIN (-5400 5125) $PN AN59
J 2
(-5410 5135);
DISPLAY 0.489362 (-5410 5135);
PAINT MONO (-5410 5135);
FORCEPROP 0 LASTPIN (-5400 5975) $PN H60
J 2
(-5410 5985);
DISPLAY 0.489362 (-5410 5985);
PAINT MONO (-5410 5985);
FORCEPROP 0 LASTPIN (-5400 5875) $PN P60
J 2
(-5410 5885);
DISPLAY 0.489362 (-5410 5885);
PAINT MONO (-5410 5885);
FORCEPROP 0 LASTPIN (-5400 5775) $PN Y60
J 2
(-5410 5785);
DISPLAY 0.489362 (-5410 5785);
PAINT MONO (-5410 5785);
FORCEPROP 0 LASTPIN (-5400 5675) $PN AF60
J 2
(-5410 5685);
DISPLAY 0.489362 (-5410 5685);
PAINT MONO (-5410 5685);
FORCEPROP 0 LASTPIN (-5400 5575) $PN AM60
J 2
(-5410 5585);
DISPLAY 0.489362 (-5410 5585);
PAINT MONO (-5410 5585);
FORCEPROP 0 LASTPIN (-5400 5475) $PN H58
J 2
(-5410 5485);
DISPLAY 0.489362 (-5410 5485);
PAINT MONO (-5410 5485);
FORCEPROP 0 LASTPIN (-5400 5375) $PN P58
J 2
(-5410 5385);
DISPLAY 0.489362 (-5410 5385);
PAINT MONO (-5410 5385);
FORCEPROP 0 LASTPIN (-5400 5275) $PN Y58
J 2
(-5410 5285);
DISPLAY 0.489362 (-5410 5285);
PAINT MONO (-5410 5285);
FORCEPROP 0 LASTPIN (-5400 5175) $PN AF58
J 2
(-5410 5185);
DISPLAY 0.489362 (-5410 5185);
PAINT MONO (-5410 5185);
FORCEPROP 0 LASTPIN (-5400 5075) $PN AM58
J 2
(-5410 5085);
DISPLAY 0.489362 (-5410 5085);
PAINT MONO (-5410 5085);
FORCEPROP 0 LASTPIN (-5400 2625) $PN BC59
J 2
(-5410 2635);
DISPLAY 0.489362 (-5410 2635);
PAINT MONO (-5410 2635);
FORCEPROP 0 LASTPIN (-5400 2525) $PN BM58
J 2
(-5410 2535);
DISPLAY 0.489362 (-5410 2535);
PAINT MONO (-5410 2535);
FORCEPROP 0 LASTPIN (-5400 2475) $PN BN60
J 2
(-5410 2485);
DISPLAY 0.489362 (-5410 2485);
PAINT MONO (-5410 2485);
FORCEPROP 0 LASTPIN (-5400 2375) $PN BP60
J 2
(-5410 2385);
DISPLAY 0.489362 (-5410 2385);
PAINT MONO (-5410 2385);
FORCEPROP 0 LASTPIN (-5400 1475) $PN BL59
J 2
(-5410 1485);
DISPLAY 0.489362 (-5410 1485);
PAINT MONO (-5410 1485);
FORCEPROP 0 LASTPIN (-5400 1425) $PN BM60
J 2
(-5410 1435);
DISPLAY 0.489362 (-5410 1435);
PAINT MONO (-5410 1435);
FORCEPROP 0 LASTPIN (-5400 1325) $PN BR60
J 2
(-5410 1335);
DISPLAY 0.489362 (-5410 1335);
PAINT MONO (-5410 1335);
FORCEPROP 0 LASTPIN (-5400 3475) $PN BG59
J 2
(-5410 3485);
DISPLAY 0.489362 (-5410 3485);
PAINT MONO (-5410 3485);
FORCEPROP 0 LASTPIN (-5400 3425) $PN BH58
J 2
(-5410 3435);
DISPLAY 0.489362 (-5410 3435);
PAINT MONO (-5410 3435);
FORCEPROP 0 LASTPIN (-5400 3375) $PN BH60
J 2
(-5410 3385);
DISPLAY 0.489362 (-5410 3385);
PAINT MONO (-5410 3385);
FORCEPROP 0 LASTPIN (-5400 3325) $PN BJ60
J 2
(-5410 3335);
DISPLAY 0.489362 (-5410 3335);
PAINT MONO (-5410 3335);
FORCEPROP 0 LASTPIN (-5400 3275) $PN BJ59
J 2
(-5410 3285);
DISPLAY 0.489362 (-5410 3285);
PAINT MONO (-5410 3285);
FORCEPROP 0 LASTPIN (-5400 3225) $PN BK58
J 2
(-5410 3235);
DISPLAY 0.489362 (-5410 3235);
PAINT MONO (-5410 3235);
FORCEPROP 0 LASTPIN (-5400 3175) $PN BK60
J 2
(-5410 3185);
DISPLAY 0.489362 (-5410 3185);
PAINT MONO (-5410 3185);
FORCEPROP 0 LASTPIN (-3800 1975) $PN BY60
J 0
(-3790 1985);
DISPLAY 0.489362 (-3790 1985);
PAINT MONO (-3790 1985);
FORCEPROP 0 LASTPIN (-3800 1925) $PN CA59
J 0
(-3790 1935);
DISPLAY 0.489362 (-3790 1935);
PAINT MONO (-3790 1935);
FORCEPROP 0 LASTPIN (-3800 1875) $PN CA60
J 0
(-3790 1885);
DISPLAY 0.489362 (-3790 1885);
PAINT MONO (-3790 1885);
FORCEPROP 0 LASTPIN (-3800 1825) $PN CB58
J 0
(-3790 1835);
DISPLAY 0.489362 (-3790 1835);
PAINT MONO (-3790 1835);
FORCEPROP 0 LASTPIN (-3800 1775) $PN BT60
J 0
(-3790 1785);
DISPLAY 0.489362 (-3790 1785);
PAINT MONO (-3790 1785);
FORCEPROP 0 LASTPIN (-3800 1725) $PN BU59
J 0
(-3790 1735);
DISPLAY 0.489362 (-3790 1735);
PAINT MONO (-3790 1735);
FORCEPROP 0 LASTPIN (-3800 1675) $PN BU60
J 0
(-3790 1685);
DISPLAY 0.489362 (-3790 1685);
PAINT MONO (-3790 1685);
FORCEPROP 0 LASTPIN (-3800 1625) $PN BV58
J 0
(-3790 1635);
DISPLAY 0.489362 (-3790 1635);
PAINT MONO (-3790 1635);
FORCEPROP 0 LASTPIN (-3800 4225) $PN CB60
J 0
(-3790 4235);
DISPLAY 0.489362 (-3790 4235);
PAINT MONO (-3790 4235);
FORCEPROP 0 LASTPIN (-3800 4175) $PN CC59
J 0
(-3790 4185);
DISPLAY 0.489362 (-3790 4185);
PAINT MONO (-3790 4185);
FORCEPROP 0 LASTPIN (-3800 4125) $PN CC60
J 0
(-3790 4135);
DISPLAY 0.489362 (-3790 4135);
PAINT MONO (-3790 4135);
FORCEPROP 0 LASTPIN (-3800 4075) $PN CD58
J 0
(-3790 4085);
DISPLAY 0.489362 (-3790 4085);
PAINT MONO (-3790 4085);
FORCEPROP 0 LASTPIN (-3800 4025) $PN CF60
J 0
(-3790 4035);
DISPLAY 0.489362 (-3790 4035);
PAINT MONO (-3790 4035);
FORCEPROP 0 LASTPIN (-3800 3975) $PN CG59
J 0
(-3790 3985);
DISPLAY 0.489362 (-3790 3985);
PAINT MONO (-3790 3985);
FORCEPROP 0 LASTPIN (-3800 3925) $PN CG60
J 0
(-3790 3935);
DISPLAY 0.489362 (-3790 3935);
PAINT MONO (-3790 3935);
FORCEPROP 0 LASTPIN (-3800 3875) $PN CH58
J 0
(-3790 3885);
DISPLAY 0.489362 (-3790 3885);
PAINT MONO (-3790 3885);
FORCEPROP 0 LASTPIN (-3800 3775) $PN CH60
J 0
(-3790 3785);
DISPLAY 0.489362 (-3790 3785);
PAINT MONO (-3790 3785);
FORCEPROP 0 LASTPIN (-3800 3725) $PN CJ59
J 0
(-3790 3735);
DISPLAY 0.489362 (-3790 3735);
PAINT MONO (-3790 3735);
FORCEPROP 0 LASTPIN (-3800 3675) $PN CJ60
J 0
(-3790 3685);
DISPLAY 0.489362 (-3790 3685);
PAINT MONO (-3790 3685);
FORCEPROP 0 LASTPIN (-3800 3625) $PN CK58
J 0
(-3790 3635);
DISPLAY 0.489362 (-3790 3635);
PAINT MONO (-3790 3635);
FORCEPROP 0 LASTPIN (-3800 3575) $PN CM60
J 0
(-3790 3585);
DISPLAY 0.489362 (-3790 3585);
PAINT MONO (-3790 3585);
FORCEPROP 0 LASTPIN (-3800 3525) $PN CN59
J 0
(-3790 3535);
DISPLAY 0.489362 (-3790 3535);
PAINT MONO (-3790 3535);
FORCEPROP 0 LASTPIN (-3800 3475) $PN CN60
J 0
(-3790 3485);
DISPLAY 0.489362 (-3790 3485);
PAINT MONO (-3790 3485);
FORCEPROP 0 LASTPIN (-3800 3425) $PN CP58
J 0
(-3790 3435);
DISPLAY 0.489362 (-3790 3435);
PAINT MONO (-3790 3435);
FORCEPROP 0 LASTPIN (-3800 3325) $PN CP60
J 0
(-3790 3335);
DISPLAY 0.489362 (-3790 3335);
PAINT MONO (-3790 3335);
FORCEPROP 0 LASTPIN (-3800 3275) $PN CR59
J 0
(-3790 3285);
DISPLAY 0.489362 (-3790 3285);
PAINT MONO (-3790 3285);
FORCEPROP 0 LASTPIN (-3800 3225) $PN CR60
J 0
(-3790 3235);
DISPLAY 0.489362 (-3790 3235);
PAINT MONO (-3790 3235);
FORCEPROP 0 LASTPIN (-3800 3175) $PN CT58
J 0
(-3790 3185);
DISPLAY 0.489362 (-3790 3185);
PAINT MONO (-3790 3185);
FORCEPROP 0 LASTPIN (-3800 3125) $PN CV60
J 0
(-3790 3135);
DISPLAY 0.489362 (-3790 3135);
PAINT MONO (-3790 3135);
FORCEPROP 0 LASTPIN (-3800 3075) $PN CW59
J 0
(-3790 3085);
DISPLAY 0.489362 (-3790 3085);
PAINT MONO (-3790 3085);
FORCEPROP 0 LASTPIN (-3800 3025) $PN CW60
J 0
(-3790 3035);
DISPLAY 0.489362 (-3790 3035);
PAINT MONO (-3790 3035);
FORCEPROP 0 LASTPIN (-3800 2975) $PN CY58
J 0
(-3790 2985);
DISPLAY 0.489362 (-3790 2985);
PAINT MONO (-3790 2985);
FORCEPROP 0 LASTPIN (-3800 2875) $PN CY60
J 0
(-3790 2885);
DISPLAY 0.489362 (-3790 2885);
PAINT MONO (-3790 2885);
FORCEPROP 0 LASTPIN (-3800 2825) $PN DA59
J 0
(-3790 2835);
DISPLAY 0.489362 (-3790 2835);
PAINT MONO (-3790 2835);
FORCEPROP 0 LASTPIN (-3800 2775) $PN DA60
J 0
(-3790 2785);
DISPLAY 0.489362 (-3790 2785);
PAINT MONO (-3790 2785);
FORCEPROP 0 LASTPIN (-3800 2725) $PN DB58
J 0
(-3790 2735);
DISPLAY 0.489362 (-3790 2735);
PAINT MONO (-3790 2735);
FORCEPROP 0 LASTPIN (-3800 2675) $PN DD60
J 0
(-3790 2685);
DISPLAY 0.489362 (-3790 2685);
PAINT MONO (-3790 2685);
FORCEPROP 0 LASTPIN (-3800 2625) $PN DE59
J 0
(-3790 2635);
DISPLAY 0.489362 (-3790 2635);
PAINT MONO (-3790 2635);
FORCEPROP 0 LASTPIN (-3800 2575) $PN DE60
J 0
(-3790 2585);
DISPLAY 0.489362 (-3790 2585);
PAINT MONO (-3790 2585);
FORCEPROP 0 LASTPIN (-3800 2525) $PN DF60
J 0
(-3790 2535);
DISPLAY 0.489362 (-3790 2535);
PAINT MONO (-3790 2535);
FORCEPROP 0 LASTPIN (-5400 4975) $PN CD60
J 2
(-5410 4985);
DISPLAY 0.489362 (-5410 4985);
PAINT MONO (-5410 4985);
FORCEPROP 0 LASTPIN (-5400 4875) $PN CK60
J 2
(-5410 4885);
DISPLAY 0.489362 (-5410 4885);
PAINT MONO (-5410 4885);
FORCEPROP 0 LASTPIN (-5400 4775) $PN CT60
J 2
(-5410 4785);
DISPLAY 0.489362 (-5410 4785);
PAINT MONO (-5410 4785);
FORCEPROP 0 LASTPIN (-5400 4675) $PN DB60
J 2
(-5410 4685);
DISPLAY 0.489362 (-5410 4685);
PAINT MONO (-5410 4685);
FORCEPROP 0 LASTPIN (-5400 4575) $PN BY58
J 2
(-5410 4585);
DISPLAY 0.489362 (-5410 4585);
PAINT MONO (-5410 4585);
FORCEPROP 0 LASTPIN (-5400 4475) $PN CF58
J 2
(-5410 4485);
DISPLAY 0.489362 (-5410 4485);
PAINT MONO (-5410 4485);
FORCEPROP 0 LASTPIN (-5400 4375) $PN CM58
J 2
(-5410 4385);
DISPLAY 0.489362 (-5410 4385);
PAINT MONO (-5410 4385);
FORCEPROP 0 LASTPIN (-5400 4275) $PN CV58
J 2
(-5410 4285);
DISPLAY 0.489362 (-5410 4285);
PAINT MONO (-5410 4285);
FORCEPROP 0 LASTPIN (-5400 4175) $PN DD58
J 2
(-5410 4185);
DISPLAY 0.489362 (-5410 4185);
PAINT MONO (-5410 4185);
FORCEPROP 0 LASTPIN (-5400 4075) $PN BV60
J 2
(-5410 4085);
DISPLAY 0.489362 (-5410 4085);
PAINT MONO (-5410 4085);
FORCEPROP 0 LASTPIN (-5400 4925) $PN CE60
J 2
(-5410 4935);
DISPLAY 0.489362 (-5410 4935);
PAINT MONO (-5410 4935);
FORCEPROP 0 LASTPIN (-5400 4825) $PN CL60
J 2
(-5410 4835);
DISPLAY 0.489362 (-5410 4835);
PAINT MONO (-5410 4835);
FORCEPROP 0 LASTPIN (-5400 4725) $PN CU60
J 2
(-5410 4735);
DISPLAY 0.489362 (-5410 4735);
PAINT MONO (-5410 4735);
FORCEPROP 0 LASTPIN (-5400 4625) $PN DC60
J 2
(-5410 4635);
DISPLAY 0.489362 (-5410 4635);
PAINT MONO (-5410 4635);
FORCEPROP 0 LASTPIN (-5400 4525) $PN BW59
J 2
(-5410 4535);
DISPLAY 0.489362 (-5410 4535);
PAINT MONO (-5410 4535);
FORCEPROP 0 LASTPIN (-5400 4425) $PN CE59
J 2
(-5410 4435);
DISPLAY 0.489362 (-5410 4435);
PAINT MONO (-5410 4435);
FORCEPROP 0 LASTPIN (-5400 4325) $PN CL59
J 2
(-5410 4335);
DISPLAY 0.489362 (-5410 4335);
PAINT MONO (-5410 4335);
FORCEPROP 0 LASTPIN (-5400 4225) $PN CU59
J 2
(-5410 4235);
DISPLAY 0.489362 (-5410 4235);
PAINT MONO (-5410 4235);
FORCEPROP 0 LASTPIN (-5400 4125) $PN DC59
J 2
(-5410 4135);
DISPLAY 0.489362 (-5410 4135);
PAINT MONO (-5410 4135);
FORCEPROP 0 LASTPIN (-5400 4025) $PN BW60
J 2
(-5410 4035);
DISPLAY 0.489362 (-5410 4035);
PAINT MONO (-5410 4035);
FORCEPROP 0 LASTPIN (-5400 2275) $PN BL60
J 2
(-5410 2285);
DISPLAY 0.489362 (-5410 2285);
PAINT MONO (-5410 2285);
FORCEPROP 0 LASTPIN (-5400 1225) $PN BF58
J 2
(-5410 1235);
DISPLAY 0.489362 (-5410 1235);
PAINT MONO (-5410 1235);
FORCEPROP 2 LAST PART_TYPE SMLF
J 0
(-5250 6425);
DISPLAY 1.021277 (-5250 6425);
FORCEPROP 1 LAST MATERIAL IO
J 0
(-5245 6207);
DISPLAY 0.489362 (-5245 6207);
PAINT SKYBLUE (-5245 6207);
FORCEPROP 2 LAST VALUE SOCKET6096_13568-001
J 0
(-5250 6325);
DISPLAY 0.489362 (-5250 6325);
PAINT SKYBLUE (-5250 6325);
FORCEPROP 1 LAST PART_NUMBER DGA^6000030
J 0
(-5245 6334);
DISPLAY 0.489362 (-5245 6334);
PAINT SKYBLUE (-5245 6334);
FORCEPROP 2 LAST CDS_LIB pure_quanta
J 0
(-4600 3650);
DISPLAY INVISIBLE (-4600 3650);
FORCEPROP 1 LAST CDS_LMAN_SYM_OUTLINE -650,2525,650,-2525
J 0
(-4600 3650);
DISPLAY 0.468085 (-4600 3650);
PAINT GREEN (-4600 3650);
DISPLAY INVISIBLE (-4600 3650);
FORCEPROP 1 LAST NEEDS_NO_SIZE TRUE
J 0
(-4600 3650);
DISPLAY 0.723404 (-4600 3650);
PAINT GREEN (-4600 3650);
DISPLAY INVISIBLE (-4600 3650);
FORCEPROP 1 LAST PATH I159
J 0
(-4600 3650);
DISPLAY 0.723404 (-4600 3650);
PAINT GREEN (-4600 3650);
DISPLAY INVISIBLE (-4600 3650);
FORCEADD OFFPAGE..3
(-2600 6050);
FORCEPROP 2 LAST $XR0 100 
J 0
(-2386 6050);
DISPLAY 0.638298 (-2386 6050);
PAINT MONO (-2386 6050);
FORCEPROP 2 LAST PATH I160
J 0
(-2375 6100);
DISPLAY 1.021277 (-2375 6100);
DISPLAY INVISIBLE (-2375 6100);
FORCEPROP 1 LAST COMMENT_BODY TRUE
J 0
(-2650 5950);
DISPLAY 0.872340 (-2650 5950);
PAINT GREEN (-2650 5950);
DISPLAY INVISIBLE (-2650 5950);
FORCEPROP 1 LAST OFFPAGE TRUE
J 0
(-2275 5925);
DISPLAY 0.872340 (-2275 5925);
PAINT GREEN (-2275 5925);
DISPLAY INVISIBLE (-2275 5925);
FORCEPROP 2 LAST CDS_LIB mstr_standard
J 0
(-2600 6050);
DISPLAY 0.723404 (-2600 6050);
PAINT MONO (-2600 6050);
DISPLAY INVISIBLE (-2600 6050);
FORCEADD OFFPAGE..3
(-2600 4250);
FORCEPROP 2 LAST $XR0 100 
J 0
(-2386 4250);
DISPLAY 0.638298 (-2386 4250);
PAINT MONO (-2386 4250);
FORCEPROP 2 LAST PATH I161
J 0
(-2375 4300);
DISPLAY 1.021277 (-2375 4300);
DISPLAY INVISIBLE (-2375 4300);
FORCEPROP 1 LAST COMMENT_BODY TRUE
J 0
(-2650 4150);
DISPLAY 0.872340 (-2650 4150);
PAINT GREEN (-2650 4150);
DISPLAY INVISIBLE (-2650 4150);
FORCEPROP 1 LAST OFFPAGE TRUE
J 0
(-2275 4125);
DISPLAY 0.872340 (-2275 4125);
PAINT GREEN (-2275 4125);
DISPLAY INVISIBLE (-2275 4125);
FORCEPROP 2 LAST CDS_LIB mstr_standard
J 0
(-2600 4250);
DISPLAY 0.723404 (-2600 4250);
PAINT MONO (-2600 4250);
DISPLAY INVISIBLE (-2600 4250);
FORCEADD TAP..1
(-3325 5975);
FORCEPROP 3 LASTPIN (-3375 5975) SIG_NAME M_D_CPU1_SA_DQ<1>
J 0
(-3365 5985);
DISPLAY 0.659574 (-3365 5985);
PAINT MONO (-3365 5985);
DISPLAY INVISIBLE (-3365 5985);
FORCEPROP 1 LASTPIN (-3375 5975) BN 1
J 0
(-3387 5983);
DISPLAY 0.489362 (-3387 5983);
PAINT GREEN (-3387 5983);
FORCEPROP 2 LAST CDS_LIB mstr_standard
J 0
(-3325 5975);
DISPLAY 0.723404 (-3325 5975);
PAINT MONO (-3325 5975);
DISPLAY INVISIBLE (-3325 5975);
FORCEPROP 1 LAST BODY_TYPE PLUMBING
J 0
(-3325 6025);
DISPLAY 0.872340 (-3325 6025);
PAINT GREEN (-3325 6025);
DISPLAY INVISIBLE (-3325 6025);
FORCEPROP 1 LAST HDL_TAP TRUE
J 0
(-3000 5850);
DISPLAY 0.872340 (-3000 5850);
DISPLAY INVISIBLE (-3000 5850);
FORCEPROP 1 LAST PATH I162
J 0
(-3327 5975);
DISPLAY 0.872340 (-3327 5975);
PAINT GREEN (-3327 5975);
DISPLAY INVISIBLE (-3327 5975);
FORCEADD TAP..1
(-3325 5925);
FORCEPROP 3 LASTPIN (-3375 5925) SIG_NAME M_D_CPU1_SA_DQ<2>
J 0
(-3365 5935);
DISPLAY 0.659574 (-3365 5935);
PAINT MONO (-3365 5935);
DISPLAY INVISIBLE (-3365 5935);
FORCEPROP 1 LASTPIN (-3375 5925) BN 2
J 0
(-3387 5933);
DISPLAY 0.489362 (-3387 5933);
PAINT GREEN (-3387 5933);
FORCEPROP 2 LAST CDS_LIB mstr_standard
J 0
(-3325 5925);
DISPLAY 0.723404 (-3325 5925);
PAINT MONO (-3325 5925);
DISPLAY INVISIBLE (-3325 5925);
FORCEPROP 1 LAST BODY_TYPE PLUMBING
J 0
(-3325 5975);
DISPLAY 0.872340 (-3325 5975);
PAINT GREEN (-3325 5975);
DISPLAY INVISIBLE (-3325 5975);
FORCEPROP 1 LAST HDL_TAP TRUE
J 0
(-3000 5800);
DISPLAY 0.872340 (-3000 5800);
DISPLAY INVISIBLE (-3000 5800);
FORCEPROP 1 LAST PATH I163
J 0
(-3327 5925);
DISPLAY 0.872340 (-3327 5925);
PAINT GREEN (-3327 5925);
DISPLAY INVISIBLE (-3327 5925);
FORCEADD TAP..1
(-3325 6025);
FORCEPROP 3 LASTPIN (-3375 6025) SIG_NAME M_D_CPU1_SA_DQ<0>
J 0
(-3365 6035);
DISPLAY 0.659574 (-3365 6035);
PAINT MONO (-3365 6035);
DISPLAY INVISIBLE (-3365 6035);
FORCEPROP 1 LASTPIN (-3375 6025) BN 0
J 0
(-3387 6033);
DISPLAY 0.489362 (-3387 6033);
PAINT GREEN (-3387 6033);
FORCEPROP 2 LAST CDS_LIB mstr_standard
J 0
(-3325 6025);
DISPLAY 0.723404 (-3325 6025);
PAINT MONO (-3325 6025);
DISPLAY INVISIBLE (-3325 6025);
FORCEPROP 1 LAST BODY_TYPE PLUMBING
J 0
(-3325 6075);
DISPLAY 0.872340 (-3325 6075);
PAINT GREEN (-3325 6075);
DISPLAY INVISIBLE (-3325 6075);
FORCEPROP 1 LAST HDL_TAP TRUE
J 0
(-3000 5900);
DISPLAY 0.872340 (-3000 5900);
DISPLAY INVISIBLE (-3000 5900);
FORCEPROP 1 LAST PATH I164
J 0
(-3327 6025);
DISPLAY 0.872340 (-3327 6025);
PAINT GREEN (-3327 6025);
DISPLAY INVISIBLE (-3327 6025);
FORCEADD TAP..1
(-3325 5825);
FORCEPROP 3 LASTPIN (-3375 5825) SIG_NAME M_D_CPU1_SA_DQ<4>
J 0
(-3365 5835);
DISPLAY 0.659574 (-3365 5835);
PAINT MONO (-3365 5835);
DISPLAY INVISIBLE (-3365 5835);
FORCEPROP 1 LASTPIN (-3375 5825) BN 4
J 0
(-3387 5833);
DISPLAY 0.489362 (-3387 5833);
PAINT GREEN (-3387 5833);
FORCEPROP 2 LAST CDS_LIB mstr_standard
J 0
(-3325 5825);
DISPLAY 0.723404 (-3325 5825);
PAINT MONO (-3325 5825);
DISPLAY INVISIBLE (-3325 5825);
FORCEPROP 1 LAST BODY_TYPE PLUMBING
J 0
(-3325 5875);
DISPLAY 0.872340 (-3325 5875);
PAINT GREEN (-3325 5875);
DISPLAY INVISIBLE (-3325 5875);
FORCEPROP 1 LAST HDL_TAP TRUE
J 0
(-3000 5700);
DISPLAY 0.872340 (-3000 5700);
DISPLAY INVISIBLE (-3000 5700);
FORCEPROP 1 LAST PATH I165
J 0
(-3327 5825);
DISPLAY 0.872340 (-3327 5825);
PAINT GREEN (-3327 5825);
DISPLAY INVISIBLE (-3327 5825);
FORCEADD TAP..1
(-3325 5875);
FORCEPROP 3 LASTPIN (-3375 5875) SIG_NAME M_D_CPU1_SA_DQ<3>
J 0
(-3365 5885);
DISPLAY 0.659574 (-3365 5885);
PAINT MONO (-3365 5885);
DISPLAY INVISIBLE (-3365 5885);
FORCEPROP 1 LASTPIN (-3375 5875) BN 3
J 0
(-3387 5883);
DISPLAY 0.489362 (-3387 5883);
PAINT GREEN (-3387 5883);
FORCEPROP 2 LAST CDS_LIB mstr_standard
J 0
(-3325 5875);
DISPLAY 0.723404 (-3325 5875);
PAINT MONO (-3325 5875);
DISPLAY INVISIBLE (-3325 5875);
FORCEPROP 1 LAST BODY_TYPE PLUMBING
J 0
(-3325 5925);
DISPLAY 0.872340 (-3325 5925);
PAINT GREEN (-3325 5925);
DISPLAY INVISIBLE (-3325 5925);
FORCEPROP 1 LAST HDL_TAP TRUE
J 0
(-3000 5750);
DISPLAY 0.872340 (-3000 5750);
DISPLAY INVISIBLE (-3000 5750);
FORCEPROP 1 LAST PATH I166
J 0
(-3327 5875);
DISPLAY 0.872340 (-3327 5875);
PAINT GREEN (-3327 5875);
DISPLAY INVISIBLE (-3327 5875);
FORCEADD TAP..1
(-3325 5775);
FORCEPROP 3 LASTPIN (-3375 5775) SIG_NAME M_D_CPU1_SA_DQ<5>
J 0
(-3365 5785);
DISPLAY 0.659574 (-3365 5785);
PAINT MONO (-3365 5785);
DISPLAY INVISIBLE (-3365 5785);
FORCEPROP 1 LASTPIN (-3375 5775) BN 5
J 0
(-3387 5783);
DISPLAY 0.489362 (-3387 5783);
PAINT GREEN (-3387 5783);
FORCEPROP 2 LAST CDS_LIB mstr_standard
J 0
(-3325 5775);
DISPLAY 0.723404 (-3325 5775);
PAINT MONO (-3325 5775);
DISPLAY INVISIBLE (-3325 5775);
FORCEPROP 1 LAST BODY_TYPE PLUMBING
J 0
(-3325 5825);
DISPLAY 0.872340 (-3325 5825);
PAINT GREEN (-3325 5825);
DISPLAY INVISIBLE (-3325 5825);
FORCEPROP 1 LAST HDL_TAP TRUE
J 0
(-3000 5650);
DISPLAY 0.872340 (-3000 5650);
DISPLAY INVISIBLE (-3000 5650);
FORCEPROP 1 LAST PATH I167
J 0
(-3327 5775);
DISPLAY 0.872340 (-3327 5775);
PAINT GREEN (-3327 5775);
DISPLAY INVISIBLE (-3327 5775);
FORCEADD TAP..1
(-3325 5725);
FORCEPROP 3 LASTPIN (-3375 5725) SIG_NAME M_D_CPU1_SA_DQ<6>
J 0
(-3365 5735);
DISPLAY 0.659574 (-3365 5735);
PAINT MONO (-3365 5735);
DISPLAY INVISIBLE (-3365 5735);
FORCEPROP 1 LASTPIN (-3375 5725) BN 6
J 0
(-3387 5733);
DISPLAY 0.489362 (-3387 5733);
PAINT GREEN (-3387 5733);
FORCEPROP 2 LAST CDS_LIB mstr_standard
J 0
(-3325 5725);
DISPLAY 0.723404 (-3325 5725);
PAINT MONO (-3325 5725);
DISPLAY INVISIBLE (-3325 5725);
FORCEPROP 1 LAST BODY_TYPE PLUMBING
J 0
(-3325 5775);
DISPLAY 0.872340 (-3325 5775);
PAINT GREEN (-3325 5775);
DISPLAY INVISIBLE (-3325 5775);
FORCEPROP 1 LAST HDL_TAP TRUE
J 0
(-3000 5600);
DISPLAY 0.872340 (-3000 5600);
DISPLAY INVISIBLE (-3000 5600);
FORCEPROP 1 LAST PATH I168
J 0
(-3327 5725);
DISPLAY 0.872340 (-3327 5725);
PAINT GREEN (-3327 5725);
DISPLAY INVISIBLE (-3327 5725);
FORCEADD TAP..1
(-3325 5675);
FORCEPROP 3 LASTPIN (-3375 5675) SIG_NAME M_D_CPU1_SA_DQ<7>
J 0
(-3365 5685);
DISPLAY 0.659574 (-3365 5685);
PAINT MONO (-3365 5685);
DISPLAY INVISIBLE (-3365 5685);
FORCEPROP 1 LASTPIN (-3375 5675) BN 7
J 0
(-3387 5683);
DISPLAY 0.489362 (-3387 5683);
PAINT GREEN (-3387 5683);
FORCEPROP 2 LAST CDS_LIB mstr_standard
J 0
(-3325 5675);
DISPLAY 0.723404 (-3325 5675);
PAINT MONO (-3325 5675);
DISPLAY INVISIBLE (-3325 5675);
FORCEPROP 1 LAST BODY_TYPE PLUMBING
J 0
(-3325 5725);
DISPLAY 0.872340 (-3325 5725);
PAINT GREEN (-3325 5725);
DISPLAY INVISIBLE (-3325 5725);
FORCEPROP 1 LAST HDL_TAP TRUE
J 0
(-3000 5550);
DISPLAY 0.872340 (-3000 5550);
DISPLAY INVISIBLE (-3000 5550);
FORCEPROP 1 LAST PATH I169
J 0
(-3327 5675);
DISPLAY 0.872340 (-3327 5675);
PAINT GREEN (-3327 5675);
DISPLAY INVISIBLE (-3327 5675);
FORCEADD TAP..1
(-3325 5425);
FORCEPROP 3 LASTPIN (-3375 5425) SIG_NAME M_D_CPU1_SA_DQ<11>
J 0
(-3365 5435);
DISPLAY 0.659574 (-3365 5435);
PAINT MONO (-3365 5435);
DISPLAY INVISIBLE (-3365 5435);
FORCEPROP 1 LASTPIN (-3375 5425) BN 11
J 0
(-3387 5433);
DISPLAY 0.489362 (-3387 5433);
PAINT GREEN (-3387 5433);
FORCEPROP 2 LAST CDS_LIB mstr_standard
J 0
(-3325 5425);
DISPLAY 0.723404 (-3325 5425);
PAINT MONO (-3325 5425);
DISPLAY INVISIBLE (-3325 5425);
FORCEPROP 1 LAST BODY_TYPE PLUMBING
J 0
(-3325 5475);
DISPLAY 0.872340 (-3325 5475);
PAINT GREEN (-3325 5475);
DISPLAY INVISIBLE (-3325 5475);
FORCEPROP 1 LAST HDL_TAP TRUE
J 0
(-3000 5300);
DISPLAY 0.872340 (-3000 5300);
DISPLAY INVISIBLE (-3000 5300);
FORCEPROP 1 LAST PATH I170
J 0
(-3327 5425);
DISPLAY 0.872340 (-3327 5425);
PAINT GREEN (-3327 5425);
DISPLAY INVISIBLE (-3327 5425);
FORCEADD TAP..1
(-3325 5475);
FORCEPROP 3 LASTPIN (-3375 5475) SIG_NAME M_D_CPU1_SA_DQ<10>
J 0
(-3365 5485);
DISPLAY 0.659574 (-3365 5485);
PAINT MONO (-3365 5485);
DISPLAY INVISIBLE (-3365 5485);
FORCEPROP 1 LASTPIN (-3375 5475) BN 10
J 0
(-3387 5483);
DISPLAY 0.489362 (-3387 5483);
PAINT GREEN (-3387 5483);
FORCEPROP 2 LAST CDS_LIB mstr_standard
J 0
(-3325 5475);
DISPLAY 0.723404 (-3325 5475);
PAINT MONO (-3325 5475);
DISPLAY INVISIBLE (-3325 5475);
FORCEPROP 1 LAST BODY_TYPE PLUMBING
J 0
(-3325 5525);
DISPLAY 0.872340 (-3325 5525);
PAINT GREEN (-3325 5525);
DISPLAY INVISIBLE (-3325 5525);
FORCEPROP 1 LAST HDL_TAP TRUE
J 0
(-3000 5350);
DISPLAY 0.872340 (-3000 5350);
DISPLAY INVISIBLE (-3000 5350);
FORCEPROP 1 LAST PATH I171
J 0
(-3327 5475);
DISPLAY 0.872340 (-3327 5475);
PAINT GREEN (-3327 5475);
DISPLAY INVISIBLE (-3327 5475);
FORCEADD TAP..1
(-3325 5525);
FORCEPROP 3 LASTPIN (-3375 5525) SIG_NAME M_D_CPU1_SA_DQ<9>
J 0
(-3365 5535);
DISPLAY 0.659574 (-3365 5535);
PAINT MONO (-3365 5535);
DISPLAY INVISIBLE (-3365 5535);
FORCEPROP 1 LASTPIN (-3375 5525) BN 9
J 0
(-3387 5533);
DISPLAY 0.489362 (-3387 5533);
PAINT GREEN (-3387 5533);
FORCEPROP 2 LAST CDS_LIB mstr_standard
J 0
(-3325 5525);
DISPLAY 0.723404 (-3325 5525);
PAINT MONO (-3325 5525);
DISPLAY INVISIBLE (-3325 5525);
FORCEPROP 1 LAST BODY_TYPE PLUMBING
J 0
(-3325 5575);
DISPLAY 0.872340 (-3325 5575);
PAINT GREEN (-3325 5575);
DISPLAY INVISIBLE (-3325 5575);
FORCEPROP 1 LAST HDL_TAP TRUE
J 0
(-3000 5400);
DISPLAY 0.872340 (-3000 5400);
DISPLAY INVISIBLE (-3000 5400);
FORCEPROP 1 LAST PATH I172
J 0
(-3327 5525);
DISPLAY 0.872340 (-3327 5525);
PAINT GREEN (-3327 5525);
DISPLAY INVISIBLE (-3327 5525);
FORCEADD TAP..1
(-3325 5575);
FORCEPROP 3 LASTPIN (-3375 5575) SIG_NAME M_D_CPU1_SA_DQ<8>
J 0
(-3365 5585);
DISPLAY 0.659574 (-3365 5585);
PAINT MONO (-3365 5585);
DISPLAY INVISIBLE (-3365 5585);
FORCEPROP 1 LASTPIN (-3375 5575) BN 8
J 0
(-3387 5583);
DISPLAY 0.489362 (-3387 5583);
PAINT GREEN (-3387 5583);
FORCEPROP 2 LAST CDS_LIB mstr_standard
J 0
(-3325 5575);
DISPLAY 0.723404 (-3325 5575);
PAINT MONO (-3325 5575);
DISPLAY INVISIBLE (-3325 5575);
FORCEPROP 1 LAST BODY_TYPE PLUMBING
J 0
(-3325 5625);
DISPLAY 0.872340 (-3325 5625);
PAINT GREEN (-3325 5625);
DISPLAY INVISIBLE (-3325 5625);
FORCEPROP 1 LAST HDL_TAP TRUE
J 0
(-3000 5450);
DISPLAY 0.872340 (-3000 5450);
DISPLAY INVISIBLE (-3000 5450);
FORCEPROP 1 LAST PATH I173
J 0
(-3327 5575);
DISPLAY 0.872340 (-3327 5575);
PAINT GREEN (-3327 5575);
DISPLAY INVISIBLE (-3327 5575);
FORCEADD TAP..1
(-3325 5125);
FORCEPROP 3 LASTPIN (-3375 5125) SIG_NAME M_D_CPU1_SA_DQ<16>
J 0
(-3365 5135);
DISPLAY 0.659574 (-3365 5135);
PAINT MONO (-3365 5135);
DISPLAY INVISIBLE (-3365 5135);
FORCEPROP 1 LASTPIN (-3375 5125) BN 16
J 0
(-3387 5133);
DISPLAY 0.489362 (-3387 5133);
PAINT GREEN (-3387 5133);
FORCEPROP 2 LAST CDS_LIB mstr_standard
J 0
(-3325 5125);
DISPLAY 0.723404 (-3325 5125);
PAINT MONO (-3325 5125);
DISPLAY INVISIBLE (-3325 5125);
FORCEPROP 1 LAST BODY_TYPE PLUMBING
J 0
(-3325 5175);
DISPLAY 0.872340 (-3325 5175);
PAINT GREEN (-3325 5175);
DISPLAY INVISIBLE (-3325 5175);
FORCEPROP 1 LAST HDL_TAP TRUE
J 0
(-3000 5000);
DISPLAY 0.872340 (-3000 5000);
DISPLAY INVISIBLE (-3000 5000);
FORCEPROP 1 LAST PATH I174
J 0
(-3327 5125);
DISPLAY 0.872340 (-3327 5125);
PAINT GREEN (-3327 5125);
DISPLAY INVISIBLE (-3327 5125);
FORCEADD TAP..1
(-3325 5225);
FORCEPROP 3 LASTPIN (-3375 5225) SIG_NAME M_D_CPU1_SA_DQ<15>
J 0
(-3365 5235);
DISPLAY 0.659574 (-3365 5235);
PAINT MONO (-3365 5235);
DISPLAY INVISIBLE (-3365 5235);
FORCEPROP 1 LASTPIN (-3375 5225) BN 15
J 0
(-3387 5233);
DISPLAY 0.489362 (-3387 5233);
PAINT GREEN (-3387 5233);
FORCEPROP 2 LAST CDS_LIB mstr_standard
J 0
(-3325 5225);
DISPLAY 0.723404 (-3325 5225);
PAINT MONO (-3325 5225);
DISPLAY INVISIBLE (-3325 5225);
FORCEPROP 1 LAST BODY_TYPE PLUMBING
J 0
(-3325 5275);
DISPLAY 0.872340 (-3325 5275);
PAINT GREEN (-3325 5275);
DISPLAY INVISIBLE (-3325 5275);
FORCEPROP 1 LAST HDL_TAP TRUE
J 0
(-3000 5100);
DISPLAY 0.872340 (-3000 5100);
DISPLAY INVISIBLE (-3000 5100);
FORCEPROP 1 LAST PATH I175
J 0
(-3327 5225);
DISPLAY 0.872340 (-3327 5225);
PAINT GREEN (-3327 5225);
DISPLAY INVISIBLE (-3327 5225);
FORCEADD TAP..1
(-3325 5275);
FORCEPROP 3 LASTPIN (-3375 5275) SIG_NAME M_D_CPU1_SA_DQ<14>
J 0
(-3365 5285);
DISPLAY 0.659574 (-3365 5285);
PAINT MONO (-3365 5285);
DISPLAY INVISIBLE (-3365 5285);
FORCEPROP 1 LASTPIN (-3375 5275) BN 14
J 0
(-3387 5283);
DISPLAY 0.489362 (-3387 5283);
PAINT GREEN (-3387 5283);
FORCEPROP 2 LAST CDS_LIB mstr_standard
J 0
(-3325 5275);
DISPLAY 0.723404 (-3325 5275);
PAINT MONO (-3325 5275);
DISPLAY INVISIBLE (-3325 5275);
FORCEPROP 1 LAST BODY_TYPE PLUMBING
J 0
(-3325 5325);
DISPLAY 0.872340 (-3325 5325);
PAINT GREEN (-3325 5325);
DISPLAY INVISIBLE (-3325 5325);
FORCEPROP 1 LAST HDL_TAP TRUE
J 0
(-3000 5150);
DISPLAY 0.872340 (-3000 5150);
DISPLAY INVISIBLE (-3000 5150);
FORCEPROP 1 LAST PATH I176
J 0
(-3327 5275);
DISPLAY 0.872340 (-3327 5275);
PAINT GREEN (-3327 5275);
DISPLAY INVISIBLE (-3327 5275);
FORCEADD TAP..1
(-3325 5375);
FORCEPROP 3 LASTPIN (-3375 5375) SIG_NAME M_D_CPU1_SA_DQ<12>
J 0
(-3365 5385);
DISPLAY 0.659574 (-3365 5385);
PAINT MONO (-3365 5385);
DISPLAY INVISIBLE (-3365 5385);
FORCEPROP 1 LASTPIN (-3375 5375) BN 12
J 0
(-3387 5383);
DISPLAY 0.489362 (-3387 5383);
PAINT GREEN (-3387 5383);
FORCEPROP 2 LAST CDS_LIB mstr_standard
J 0
(-3325 5375);
DISPLAY 0.723404 (-3325 5375);
PAINT MONO (-3325 5375);
DISPLAY INVISIBLE (-3325 5375);
FORCEPROP 1 LAST BODY_TYPE PLUMBING
J 0
(-3325 5425);
DISPLAY 0.872340 (-3325 5425);
PAINT GREEN (-3325 5425);
DISPLAY INVISIBLE (-3325 5425);
FORCEPROP 1 LAST HDL_TAP TRUE
J 0
(-3000 5250);
DISPLAY 0.872340 (-3000 5250);
DISPLAY INVISIBLE (-3000 5250);
FORCEPROP 1 LAST PATH I177
J 0
(-3327 5375);
DISPLAY 0.872340 (-3327 5375);
PAINT GREEN (-3327 5375);
DISPLAY INVISIBLE (-3327 5375);
FORCEADD TAP..1
(-3325 5325);
FORCEPROP 3 LASTPIN (-3375 5325) SIG_NAME M_D_CPU1_SA_DQ<13>
J 0
(-3365 5335);
DISPLAY 0.659574 (-3365 5335);
PAINT MONO (-3365 5335);
DISPLAY INVISIBLE (-3365 5335);
FORCEPROP 1 LASTPIN (-3375 5325) BN 13
J 0
(-3387 5333);
DISPLAY 0.489362 (-3387 5333);
PAINT GREEN (-3387 5333);
FORCEPROP 2 LAST CDS_LIB mstr_standard
J 0
(-3325 5325);
DISPLAY 0.723404 (-3325 5325);
PAINT MONO (-3325 5325);
DISPLAY INVISIBLE (-3325 5325);
FORCEPROP 1 LAST BODY_TYPE PLUMBING
J 0
(-3325 5375);
DISPLAY 0.872340 (-3325 5375);
PAINT GREEN (-3325 5375);
DISPLAY INVISIBLE (-3325 5375);
FORCEPROP 1 LAST HDL_TAP TRUE
J 0
(-3000 5200);
DISPLAY 0.872340 (-3000 5200);
DISPLAY INVISIBLE (-3000 5200);
FORCEPROP 1 LAST PATH I178
J 0
(-3327 5325);
DISPLAY 0.872340 (-3327 5325);
PAINT GREEN (-3327 5325);
DISPLAY INVISIBLE (-3327 5325);
FORCEADD TAP..1
(-3325 4925);
FORCEPROP 3 LASTPIN (-3375 4925) SIG_NAME M_D_CPU1_SA_DQ<20>
J 0
(-3365 4935);
DISPLAY 0.659574 (-3365 4935);
PAINT MONO (-3365 4935);
DISPLAY INVISIBLE (-3365 4935);
FORCEPROP 1 LASTPIN (-3375 4925) BN 20
J 0
(-3387 4933);
DISPLAY 0.489362 (-3387 4933);
PAINT GREEN (-3387 4933);
FORCEPROP 2 LAST CDS_LIB mstr_standard
J 0
(-3325 4925);
DISPLAY 0.723404 (-3325 4925);
PAINT MONO (-3325 4925);
DISPLAY INVISIBLE (-3325 4925);
FORCEPROP 1 LAST BODY_TYPE PLUMBING
J 0
(-3325 4975);
DISPLAY 0.872340 (-3325 4975);
PAINT GREEN (-3325 4975);
DISPLAY INVISIBLE (-3325 4975);
FORCEPROP 1 LAST HDL_TAP TRUE
J 0
(-3000 4800);
DISPLAY 0.872340 (-3000 4800);
DISPLAY INVISIBLE (-3000 4800);
FORCEPROP 1 LAST PATH I179
J 0
(-3327 4925);
DISPLAY 0.872340 (-3327 4925);
PAINT GREEN (-3327 4925);
DISPLAY INVISIBLE (-3327 4925);
FORCEADD TAP..1
(-3325 4875);
FORCEPROP 3 LASTPIN (-3375 4875) SIG_NAME M_D_CPU1_SA_DQ<21>
J 0
(-3365 4885);
DISPLAY 0.659574 (-3365 4885);
PAINT MONO (-3365 4885);
DISPLAY INVISIBLE (-3365 4885);
FORCEPROP 1 LASTPIN (-3375 4875) BN 21
J 0
(-3387 4883);
DISPLAY 0.489362 (-3387 4883);
PAINT GREEN (-3387 4883);
FORCEPROP 2 LAST CDS_LIB mstr_standard
J 0
(-3325 4875);
DISPLAY 0.723404 (-3325 4875);
PAINT MONO (-3325 4875);
DISPLAY INVISIBLE (-3325 4875);
FORCEPROP 1 LAST BODY_TYPE PLUMBING
J 0
(-3325 4925);
DISPLAY 0.872340 (-3325 4925);
PAINT GREEN (-3325 4925);
DISPLAY INVISIBLE (-3325 4925);
FORCEPROP 1 LAST HDL_TAP TRUE
J 0
(-3000 4750);
DISPLAY 0.872340 (-3000 4750);
DISPLAY INVISIBLE (-3000 4750);
FORCEPROP 1 LAST PATH I180
J 0
(-3327 4875);
DISPLAY 0.872340 (-3327 4875);
PAINT GREEN (-3327 4875);
DISPLAY INVISIBLE (-3327 4875);
FORCEADD TAP..1
(-3325 4975);
FORCEPROP 3 LASTPIN (-3375 4975) SIG_NAME M_D_CPU1_SA_DQ<19>
J 0
(-3365 4985);
DISPLAY 0.659574 (-3365 4985);
PAINT MONO (-3365 4985);
DISPLAY INVISIBLE (-3365 4985);
FORCEPROP 1 LASTPIN (-3375 4975) BN 19
J 0
(-3387 4983);
DISPLAY 0.489362 (-3387 4983);
PAINT GREEN (-3387 4983);
FORCEPROP 2 LAST CDS_LIB mstr_standard
J 0
(-3325 4975);
DISPLAY 0.723404 (-3325 4975);
PAINT MONO (-3325 4975);
DISPLAY INVISIBLE (-3325 4975);
FORCEPROP 1 LAST BODY_TYPE PLUMBING
J 0
(-3325 5025);
DISPLAY 0.872340 (-3325 5025);
PAINT GREEN (-3325 5025);
DISPLAY INVISIBLE (-3325 5025);
FORCEPROP 1 LAST HDL_TAP TRUE
J 0
(-3000 4850);
DISPLAY 0.872340 (-3000 4850);
DISPLAY INVISIBLE (-3000 4850);
FORCEPROP 1 LAST PATH I181
J 0
(-3327 4975);
DISPLAY 0.872340 (-3327 4975);
PAINT GREEN (-3327 4975);
DISPLAY INVISIBLE (-3327 4975);
FORCEADD TAP..1
(-3325 5025);
FORCEPROP 3 LASTPIN (-3375 5025) SIG_NAME M_D_CPU1_SA_DQ<18>
J 0
(-3365 5035);
DISPLAY 0.659574 (-3365 5035);
PAINT MONO (-3365 5035);
DISPLAY INVISIBLE (-3365 5035);
FORCEPROP 1 LASTPIN (-3375 5025) BN 18
J 0
(-3387 5033);
DISPLAY 0.489362 (-3387 5033);
PAINT GREEN (-3387 5033);
FORCEPROP 2 LAST CDS_LIB mstr_standard
J 0
(-3325 5025);
DISPLAY 0.723404 (-3325 5025);
PAINT MONO (-3325 5025);
DISPLAY INVISIBLE (-3325 5025);
FORCEPROP 1 LAST BODY_TYPE PLUMBING
J 0
(-3325 5075);
DISPLAY 0.872340 (-3325 5075);
PAINT GREEN (-3325 5075);
DISPLAY INVISIBLE (-3325 5075);
FORCEPROP 1 LAST HDL_TAP TRUE
J 0
(-3000 4900);
DISPLAY 0.872340 (-3000 4900);
DISPLAY INVISIBLE (-3000 4900);
FORCEPROP 1 LAST PATH I182
J 0
(-3327 5025);
DISPLAY 0.872340 (-3327 5025);
PAINT GREEN (-3327 5025);
DISPLAY INVISIBLE (-3327 5025);
FORCEADD TAP..1
(-3325 5075);
FORCEPROP 3 LASTPIN (-3375 5075) SIG_NAME M_D_CPU1_SA_DQ<17>
J 0
(-3365 5085);
DISPLAY 0.659574 (-3365 5085);
PAINT MONO (-3365 5085);
DISPLAY INVISIBLE (-3365 5085);
FORCEPROP 1 LASTPIN (-3375 5075) BN 17
J 0
(-3387 5083);
DISPLAY 0.489362 (-3387 5083);
PAINT GREEN (-3387 5083);
FORCEPROP 2 LAST CDS_LIB mstr_standard
J 0
(-3325 5075);
DISPLAY 0.723404 (-3325 5075);
PAINT MONO (-3325 5075);
DISPLAY INVISIBLE (-3325 5075);
FORCEPROP 1 LAST BODY_TYPE PLUMBING
J 0
(-3325 5125);
DISPLAY 0.872340 (-3325 5125);
PAINT GREEN (-3325 5125);
DISPLAY INVISIBLE (-3325 5125);
FORCEPROP 1 LAST HDL_TAP TRUE
J 0
(-3000 4950);
DISPLAY 0.872340 (-3000 4950);
DISPLAY INVISIBLE (-3000 4950);
FORCEPROP 1 LAST PATH I183
J 0
(-3327 5075);
DISPLAY 0.872340 (-3327 5075);
PAINT GREEN (-3327 5075);
DISPLAY INVISIBLE (-3327 5075);
FORCEADD TAP..1
(-3325 4825);
FORCEPROP 3 LASTPIN (-3375 4825) SIG_NAME M_D_CPU1_SA_DQ<22>
J 0
(-3365 4835);
DISPLAY 0.659574 (-3365 4835);
PAINT MONO (-3365 4835);
DISPLAY INVISIBLE (-3365 4835);
FORCEPROP 1 LASTPIN (-3375 4825) BN 22
J 0
(-3387 4833);
DISPLAY 0.489362 (-3387 4833);
PAINT GREEN (-3387 4833);
FORCEPROP 2 LAST CDS_LIB mstr_standard
J 0
(-3325 4825);
DISPLAY 0.723404 (-3325 4825);
PAINT MONO (-3325 4825);
DISPLAY INVISIBLE (-3325 4825);
FORCEPROP 1 LAST BODY_TYPE PLUMBING
J 0
(-3325 4875);
DISPLAY 0.872340 (-3325 4875);
PAINT GREEN (-3325 4875);
DISPLAY INVISIBLE (-3325 4875);
FORCEPROP 1 LAST HDL_TAP TRUE
J 0
(-3000 4700);
DISPLAY 0.872340 (-3000 4700);
DISPLAY INVISIBLE (-3000 4700);
FORCEPROP 1 LAST PATH I184
J 0
(-3327 4825);
DISPLAY 0.872340 (-3327 4825);
PAINT GREEN (-3327 4825);
DISPLAY INVISIBLE (-3327 4825);
FORCEADD TAP..1
(-3325 4775);
FORCEPROP 3 LASTPIN (-3375 4775) SIG_NAME M_D_CPU1_SA_DQ<23>
J 0
(-3365 4785);
DISPLAY 0.659574 (-3365 4785);
PAINT MONO (-3365 4785);
DISPLAY INVISIBLE (-3365 4785);
FORCEPROP 1 LASTPIN (-3375 4775) BN 23
J 0
(-3387 4783);
DISPLAY 0.489362 (-3387 4783);
PAINT GREEN (-3387 4783);
FORCEPROP 2 LAST CDS_LIB mstr_standard
J 0
(-3325 4775);
DISPLAY 0.723404 (-3325 4775);
PAINT MONO (-3325 4775);
DISPLAY INVISIBLE (-3325 4775);
FORCEPROP 1 LAST BODY_TYPE PLUMBING
J 0
(-3325 4825);
DISPLAY 0.872340 (-3325 4825);
PAINT GREEN (-3325 4825);
DISPLAY INVISIBLE (-3325 4825);
FORCEPROP 1 LAST HDL_TAP TRUE
J 0
(-3000 4650);
DISPLAY 0.872340 (-3000 4650);
DISPLAY INVISIBLE (-3000 4650);
FORCEPROP 1 LAST PATH I185
J 0
(-3327 4775);
DISPLAY 0.872340 (-3327 4775);
PAINT GREEN (-3327 4775);
DISPLAY INVISIBLE (-3327 4775);
FORCEADD TAP..1
(-3325 4675);
FORCEPROP 3 LASTPIN (-3375 4675) SIG_NAME M_D_CPU1_SA_DQ<24>
J 0
(-3365 4685);
DISPLAY 0.659574 (-3365 4685);
PAINT MONO (-3365 4685);
DISPLAY INVISIBLE (-3365 4685);
FORCEPROP 1 LASTPIN (-3375 4675) BN 24
J 0
(-3387 4683);
DISPLAY 0.489362 (-3387 4683);
PAINT GREEN (-3387 4683);
FORCEPROP 2 LAST CDS_LIB mstr_standard
J 0
(-3325 4675);
DISPLAY 0.723404 (-3325 4675);
PAINT MONO (-3325 4675);
DISPLAY INVISIBLE (-3325 4675);
FORCEPROP 1 LAST BODY_TYPE PLUMBING
J 0
(-3325 4725);
DISPLAY 0.872340 (-3325 4725);
PAINT GREEN (-3325 4725);
DISPLAY INVISIBLE (-3325 4725);
FORCEPROP 1 LAST HDL_TAP TRUE
J 0
(-3000 4550);
DISPLAY 0.872340 (-3000 4550);
DISPLAY INVISIBLE (-3000 4550);
FORCEPROP 1 LAST PATH I186
J 0
(-3327 4675);
DISPLAY 0.872340 (-3327 4675);
PAINT GREEN (-3327 4675);
DISPLAY INVISIBLE (-3327 4675);
FORCEADD TAP..1
(-3325 4625);
FORCEPROP 3 LASTPIN (-3375 4625) SIG_NAME M_D_CPU1_SA_DQ<25>
J 0
(-3365 4635);
DISPLAY 0.659574 (-3365 4635);
PAINT MONO (-3365 4635);
DISPLAY INVISIBLE (-3365 4635);
FORCEPROP 1 LASTPIN (-3375 4625) BN 25
J 0
(-3387 4633);
DISPLAY 0.489362 (-3387 4633);
PAINT GREEN (-3387 4633);
FORCEPROP 2 LAST CDS_LIB mstr_standard
J 0
(-3325 4625);
DISPLAY 0.723404 (-3325 4625);
PAINT MONO (-3325 4625);
DISPLAY INVISIBLE (-3325 4625);
FORCEPROP 1 LAST BODY_TYPE PLUMBING
J 0
(-3325 4675);
DISPLAY 0.872340 (-3325 4675);
PAINT GREEN (-3325 4675);
DISPLAY INVISIBLE (-3325 4675);
FORCEPROP 1 LAST HDL_TAP TRUE
J 0
(-3000 4500);
DISPLAY 0.872340 (-3000 4500);
DISPLAY INVISIBLE (-3000 4500);
FORCEPROP 1 LAST PATH I187
J 0
(-3327 4625);
DISPLAY 0.872340 (-3327 4625);
PAINT GREEN (-3327 4625);
DISPLAY INVISIBLE (-3327 4625);
FORCEADD TAP..1
(-3325 4425);
FORCEPROP 3 LASTPIN (-3375 4425) SIG_NAME M_D_CPU1_SA_DQ<29>
J 0
(-3365 4435);
DISPLAY 0.659574 (-3365 4435);
PAINT MONO (-3365 4435);
DISPLAY INVISIBLE (-3365 4435);
FORCEPROP 1 LASTPIN (-3375 4425) BN 29
J 0
(-3387 4433);
DISPLAY 0.489362 (-3387 4433);
PAINT GREEN (-3387 4433);
FORCEPROP 2 LAST CDS_LIB mstr_standard
J 0
(-3325 4425);
DISPLAY 0.723404 (-3325 4425);
PAINT MONO (-3325 4425);
DISPLAY INVISIBLE (-3325 4425);
FORCEPROP 1 LAST BODY_TYPE PLUMBING
J 0
(-3325 4475);
DISPLAY 0.872340 (-3325 4475);
PAINT GREEN (-3325 4475);
DISPLAY INVISIBLE (-3325 4475);
FORCEPROP 1 LAST HDL_TAP TRUE
J 0
(-3000 4300);
DISPLAY 0.872340 (-3000 4300);
DISPLAY INVISIBLE (-3000 4300);
FORCEPROP 1 LAST PATH I188
J 0
(-3327 4425);
DISPLAY 0.872340 (-3327 4425);
PAINT GREEN (-3327 4425);
DISPLAY INVISIBLE (-3327 4425);
FORCEADD TAP..1
(-3325 4375);
FORCEPROP 3 LASTPIN (-3375 4375) SIG_NAME M_D_CPU1_SA_DQ<30>
J 0
(-3365 4385);
DISPLAY 0.659574 (-3365 4385);
PAINT MONO (-3365 4385);
DISPLAY INVISIBLE (-3365 4385);
FORCEPROP 1 LASTPIN (-3375 4375) BN 30
J 0
(-3387 4383);
DISPLAY 0.489362 (-3387 4383);
PAINT GREEN (-3387 4383);
FORCEPROP 2 LAST CDS_LIB mstr_standard
J 0
(-3325 4375);
DISPLAY 0.723404 (-3325 4375);
PAINT MONO (-3325 4375);
DISPLAY INVISIBLE (-3325 4375);
FORCEPROP 1 LAST BODY_TYPE PLUMBING
J 0
(-3325 4425);
DISPLAY 0.872340 (-3325 4425);
PAINT GREEN (-3325 4425);
DISPLAY INVISIBLE (-3325 4425);
FORCEPROP 1 LAST HDL_TAP TRUE
J 0
(-3000 4250);
DISPLAY 0.872340 (-3000 4250);
DISPLAY INVISIBLE (-3000 4250);
FORCEPROP 1 LAST PATH I189
J 0
(-3327 4375);
DISPLAY 0.872340 (-3327 4375);
PAINT GREEN (-3327 4375);
DISPLAY INVISIBLE (-3327 4375);
FORCEADD TAP..1
(-3325 4475);
FORCEPROP 3 LASTPIN (-3375 4475) SIG_NAME M_D_CPU1_SA_DQ<28>
J 0
(-3365 4485);
DISPLAY 0.659574 (-3365 4485);
PAINT MONO (-3365 4485);
DISPLAY INVISIBLE (-3365 4485);
FORCEPROP 1 LASTPIN (-3375 4475) BN 28
J 0
(-3387 4483);
DISPLAY 0.489362 (-3387 4483);
PAINT GREEN (-3387 4483);
FORCEPROP 2 LAST CDS_LIB mstr_standard
J 0
(-3325 4475);
DISPLAY 0.723404 (-3325 4475);
PAINT MONO (-3325 4475);
DISPLAY INVISIBLE (-3325 4475);
FORCEPROP 1 LAST BODY_TYPE PLUMBING
J 0
(-3325 4525);
DISPLAY 0.872340 (-3325 4525);
PAINT GREEN (-3325 4525);
DISPLAY INVISIBLE (-3325 4525);
FORCEPROP 1 LAST HDL_TAP TRUE
J 0
(-3000 4350);
DISPLAY 0.872340 (-3000 4350);
DISPLAY INVISIBLE (-3000 4350);
FORCEPROP 1 LAST PATH I190
J 0
(-3327 4475);
DISPLAY 0.872340 (-3327 4475);
PAINT GREEN (-3327 4475);
DISPLAY INVISIBLE (-3327 4475);
FORCEADD TAP..1
(-3325 4575);
FORCEPROP 3 LASTPIN (-3375 4575) SIG_NAME M_D_CPU1_SA_DQ<26>
J 0
(-3365 4585);
DISPLAY 0.659574 (-3365 4585);
PAINT MONO (-3365 4585);
DISPLAY INVISIBLE (-3365 4585);
FORCEPROP 1 LASTPIN (-3375 4575) BN 26
J 0
(-3387 4583);
DISPLAY 0.489362 (-3387 4583);
PAINT GREEN (-3387 4583);
FORCEPROP 2 LAST CDS_LIB mstr_standard
J 0
(-3325 4575);
DISPLAY 0.723404 (-3325 4575);
PAINT MONO (-3325 4575);
DISPLAY INVISIBLE (-3325 4575);
FORCEPROP 1 LAST BODY_TYPE PLUMBING
J 0
(-3325 4625);
DISPLAY 0.872340 (-3325 4625);
PAINT GREEN (-3325 4625);
DISPLAY INVISIBLE (-3325 4625);
FORCEPROP 1 LAST HDL_TAP TRUE
J 0
(-3000 4450);
DISPLAY 0.872340 (-3000 4450);
DISPLAY INVISIBLE (-3000 4450);
FORCEPROP 1 LAST PATH I191
J 0
(-3327 4575);
DISPLAY 0.872340 (-3327 4575);
PAINT GREEN (-3327 4575);
DISPLAY INVISIBLE (-3327 4575);
FORCEADD TAP..1
(-3325 4525);
FORCEPROP 3 LASTPIN (-3375 4525) SIG_NAME M_D_CPU1_SA_DQ<27>
J 0
(-3365 4535);
DISPLAY 0.659574 (-3365 4535);
PAINT MONO (-3365 4535);
DISPLAY INVISIBLE (-3365 4535);
FORCEPROP 1 LASTPIN (-3375 4525) BN 27
J 0
(-3387 4533);
DISPLAY 0.489362 (-3387 4533);
PAINT GREEN (-3387 4533);
FORCEPROP 2 LAST CDS_LIB mstr_standard
J 0
(-3325 4525);
DISPLAY 0.723404 (-3325 4525);
PAINT MONO (-3325 4525);
DISPLAY INVISIBLE (-3325 4525);
FORCEPROP 1 LAST BODY_TYPE PLUMBING
J 0
(-3325 4575);
DISPLAY 0.872340 (-3325 4575);
PAINT GREEN (-3325 4575);
DISPLAY INVISIBLE (-3325 4575);
FORCEPROP 1 LAST HDL_TAP TRUE
J 0
(-3000 4400);
DISPLAY 0.872340 (-3000 4400);
DISPLAY INVISIBLE (-3000 4400);
FORCEPROP 1 LAST PATH I192
J 0
(-3327 4525);
DISPLAY 0.872340 (-3327 4525);
PAINT GREEN (-3327 4525);
DISPLAY INVISIBLE (-3327 4525);
FORCEADD TAP..1
(-3325 4175);
FORCEPROP 3 LASTPIN (-3375 4175) SIG_NAME M_D_CPU1_SB_DQ<1>
J 0
(-3365 4185);
DISPLAY 0.659574 (-3365 4185);
PAINT MONO (-3365 4185);
DISPLAY INVISIBLE (-3365 4185);
FORCEPROP 1 LASTPIN (-3375 4175) BN 1
J 0
(-3387 4183);
DISPLAY 0.489362 (-3387 4183);
PAINT GREEN (-3387 4183);
FORCEPROP 2 LAST CDS_LIB mstr_standard
J 0
(-3325 4175);
DISPLAY 0.723404 (-3325 4175);
PAINT MONO (-3325 4175);
DISPLAY INVISIBLE (-3325 4175);
FORCEPROP 1 LAST BODY_TYPE PLUMBING
J 0
(-3325 4225);
DISPLAY 0.872340 (-3325 4225);
PAINT GREEN (-3325 4225);
DISPLAY INVISIBLE (-3325 4225);
FORCEPROP 1 LAST HDL_TAP TRUE
J 0
(-3000 4050);
DISPLAY 0.872340 (-3000 4050);
DISPLAY INVISIBLE (-3000 4050);
FORCEPROP 1 LAST PATH I193
J 0
(-3327 4175);
DISPLAY 0.872340 (-3327 4175);
PAINT GREEN (-3327 4175);
DISPLAY INVISIBLE (-3327 4175);
FORCEADD TAP..1
(-3325 4325);
FORCEPROP 3 LASTPIN (-3375 4325) SIG_NAME M_D_CPU1_SA_DQ<31>
J 0
(-3365 4335);
DISPLAY 0.659574 (-3365 4335);
PAINT MONO (-3365 4335);
DISPLAY INVISIBLE (-3365 4335);
FORCEPROP 1 LASTPIN (-3375 4325) BN 31
J 0
(-3387 4333);
DISPLAY 0.489362 (-3387 4333);
PAINT GREEN (-3387 4333);
FORCEPROP 2 LAST CDS_LIB mstr_standard
J 0
(-3325 4325);
DISPLAY 0.723404 (-3325 4325);
PAINT MONO (-3325 4325);
DISPLAY INVISIBLE (-3325 4325);
FORCEPROP 1 LAST BODY_TYPE PLUMBING
J 0
(-3325 4375);
DISPLAY 0.872340 (-3325 4375);
PAINT GREEN (-3325 4375);
DISPLAY INVISIBLE (-3325 4375);
FORCEPROP 1 LAST HDL_TAP TRUE
J 0
(-3000 4200);
DISPLAY 0.872340 (-3000 4200);
DISPLAY INVISIBLE (-3000 4200);
FORCEPROP 1 LAST PATH I194
J 0
(-3327 4325);
DISPLAY 0.872340 (-3327 4325);
PAINT GREEN (-3327 4325);
DISPLAY INVISIBLE (-3327 4325);
FORCEADD TAP..1
(-3325 4125);
FORCEPROP 3 LASTPIN (-3375 4125) SIG_NAME M_D_CPU1_SB_DQ<2>
J 0
(-3365 4135);
DISPLAY 0.659574 (-3365 4135);
PAINT MONO (-3365 4135);
DISPLAY INVISIBLE (-3365 4135);
FORCEPROP 1 LASTPIN (-3375 4125) BN 2
J 0
(-3387 4133);
DISPLAY 0.489362 (-3387 4133);
PAINT GREEN (-3387 4133);
FORCEPROP 2 LAST CDS_LIB mstr_standard
J 0
(-3325 4125);
DISPLAY 0.723404 (-3325 4125);
PAINT MONO (-3325 4125);
DISPLAY INVISIBLE (-3325 4125);
FORCEPROP 1 LAST BODY_TYPE PLUMBING
J 0
(-3325 4175);
DISPLAY 0.872340 (-3325 4175);
PAINT GREEN (-3325 4175);
DISPLAY INVISIBLE (-3325 4175);
FORCEPROP 1 LAST HDL_TAP TRUE
J 0
(-3000 4000);
DISPLAY 0.872340 (-3000 4000);
DISPLAY INVISIBLE (-3000 4000);
FORCEPROP 1 LAST PATH I195
J 0
(-3327 4125);
DISPLAY 0.872340 (-3327 4125);
PAINT GREEN (-3327 4125);
DISPLAY INVISIBLE (-3327 4125);
FORCEADD TAP..1
(-3325 4225);
FORCEPROP 3 LASTPIN (-3375 4225) SIG_NAME M_D_CPU1_SB_DQ<0>
J 0
(-3365 4235);
DISPLAY 0.659574 (-3365 4235);
PAINT MONO (-3365 4235);
DISPLAY INVISIBLE (-3365 4235);
FORCEPROP 1 LASTPIN (-3375 4225) BN 0
J 0
(-3387 4233);
DISPLAY 0.489362 (-3387 4233);
PAINT GREEN (-3387 4233);
FORCEPROP 2 LAST CDS_LIB mstr_standard
J 0
(-3325 4225);
DISPLAY 0.723404 (-3325 4225);
PAINT MONO (-3325 4225);
DISPLAY INVISIBLE (-3325 4225);
FORCEPROP 1 LAST BODY_TYPE PLUMBING
J 0
(-3325 4275);
DISPLAY 0.872340 (-3325 4275);
PAINT GREEN (-3325 4275);
DISPLAY INVISIBLE (-3325 4275);
FORCEPROP 1 LAST HDL_TAP TRUE
J 0
(-3000 4100);
DISPLAY 0.872340 (-3000 4100);
DISPLAY INVISIBLE (-3000 4100);
FORCEPROP 1 LAST PATH I196
J 0
(-3327 4225);
DISPLAY 0.872340 (-3327 4225);
PAINT GREEN (-3327 4225);
DISPLAY INVISIBLE (-3327 4225);
FORCEADD OFFPAGE..6
R 2
(-2725 2475);
FORCEPROP 2 LAST $XR0 100 
J 0
(-2511 2475);
DISPLAY 0.638298 (-2511 2475);
PAINT MONO (-2511 2475);
FORCEPROP 2 LAST PATH I197
J 0
(-2500 2525);
DISPLAY 1.021277 (-2500 2525);
DISPLAY INVISIBLE (-2500 2525);
FORCEPROP 1 LAST COMMENT_BODY TRUE
J 2
(-2825 2400);
DISPLAY 0.872340 (-2825 2400);
PAINT GREEN (-2825 2400);
DISPLAY INVISIBLE (-2825 2400);
FORCEPROP 1 LAST OFFPAGE TRUE
J 2
(-3050 2350);
DISPLAY 0.872340 (-3050 2350);
PAINT GREEN (-3050 2350);
DISPLAY INVISIBLE (-3050 2350);
FORCEPROP 2 LAST CDS_LIB mstr_standard
J 2
(-2725 2475);
DISPLAY 0.723404 (-2725 2475);
PAINT MONO (-2725 2475);
DISPLAY INVISIBLE (-2725 2475);
FORCEADD TAP..1
(-3325 4025);
FORCEPROP 3 LASTPIN (-3375 4025) SIG_NAME M_D_CPU1_SB_DQ<4>
J 0
(-3365 4035);
DISPLAY 0.659574 (-3365 4035);
PAINT MONO (-3365 4035);
DISPLAY INVISIBLE (-3365 4035);
FORCEPROP 1 LASTPIN (-3375 4025) BN 4
J 0
(-3387 4033);
DISPLAY 0.489362 (-3387 4033);
PAINT GREEN (-3387 4033);
FORCEPROP 2 LAST CDS_LIB mstr_standard
J 0
(-3325 4025);
DISPLAY 0.723404 (-3325 4025);
PAINT MONO (-3325 4025);
DISPLAY INVISIBLE (-3325 4025);
FORCEPROP 1 LAST BODY_TYPE PLUMBING
J 0
(-3325 4075);
DISPLAY 0.872340 (-3325 4075);
PAINT GREEN (-3325 4075);
DISPLAY INVISIBLE (-3325 4075);
FORCEPROP 1 LAST HDL_TAP TRUE
J 0
(-3000 3900);
DISPLAY 0.872340 (-3000 3900);
DISPLAY INVISIBLE (-3000 3900);
FORCEPROP 1 LAST PATH I198
J 0
(-3327 4025);
DISPLAY 0.872340 (-3327 4025);
PAINT GREEN (-3327 4025);
DISPLAY INVISIBLE (-3327 4025);
FORCEADD TAP..1
(-3325 4075);
FORCEPROP 3 LASTPIN (-3375 4075) SIG_NAME M_D_CPU1_SB_DQ<3>
J 0
(-3365 4085);
DISPLAY 0.659574 (-3365 4085);
PAINT MONO (-3365 4085);
DISPLAY INVISIBLE (-3365 4085);
FORCEPROP 1 LASTPIN (-3375 4075) BN 3
J 0
(-3387 4083);
DISPLAY 0.489362 (-3387 4083);
PAINT GREEN (-3387 4083);
FORCEPROP 2 LAST CDS_LIB mstr_standard
J 0
(-3325 4075);
DISPLAY 0.723404 (-3325 4075);
PAINT MONO (-3325 4075);
DISPLAY INVISIBLE (-3325 4075);
FORCEPROP 1 LAST BODY_TYPE PLUMBING
J 0
(-3325 4125);
DISPLAY 0.872340 (-3325 4125);
PAINT GREEN (-3325 4125);
DISPLAY INVISIBLE (-3325 4125);
FORCEPROP 1 LAST HDL_TAP TRUE
J 0
(-3000 3950);
DISPLAY 0.872340 (-3000 3950);
DISPLAY INVISIBLE (-3000 3950);
FORCEPROP 1 LAST PATH I199
J 0
(-3327 4075);
DISPLAY 0.872340 (-3327 4075);
PAINT GREEN (-3327 4075);
DISPLAY INVISIBLE (-3327 4075);
FORCEADD TAP..1
(-3325 3975);
FORCEPROP 3 LASTPIN (-3375 3975) SIG_NAME M_D_CPU1_SB_DQ<5>
J 0
(-3365 3985);
DISPLAY 0.659574 (-3365 3985);
PAINT MONO (-3365 3985);
DISPLAY INVISIBLE (-3365 3985);
FORCEPROP 1 LASTPIN (-3375 3975) BN 5
J 0
(-3387 3983);
DISPLAY 0.489362 (-3387 3983);
PAINT GREEN (-3387 3983);
FORCEPROP 2 LAST CDS_LIB mstr_standard
J 0
(-3325 3975);
DISPLAY 0.723404 (-3325 3975);
PAINT MONO (-3325 3975);
DISPLAY INVISIBLE (-3325 3975);
FORCEPROP 1 LAST BODY_TYPE PLUMBING
J 0
(-3325 4025);
DISPLAY 0.872340 (-3325 4025);
PAINT GREEN (-3325 4025);
DISPLAY INVISIBLE (-3325 4025);
FORCEPROP 1 LAST HDL_TAP TRUE
J 0
(-3000 3850);
DISPLAY 0.872340 (-3000 3850);
DISPLAY INVISIBLE (-3000 3850);
FORCEPROP 1 LAST PATH I200
J 0
(-3327 3975);
DISPLAY 0.872340 (-3327 3975);
PAINT GREEN (-3327 3975);
DISPLAY INVISIBLE (-3327 3975);
FORCEADD TAP..1
(-3325 3925);
FORCEPROP 3 LASTPIN (-3375 3925) SIG_NAME M_D_CPU1_SB_DQ<6>
J 0
(-3365 3935);
DISPLAY 0.659574 (-3365 3935);
PAINT MONO (-3365 3935);
DISPLAY INVISIBLE (-3365 3935);
FORCEPROP 1 LASTPIN (-3375 3925) BN 6
J 0
(-3387 3933);
DISPLAY 0.489362 (-3387 3933);
PAINT GREEN (-3387 3933);
FORCEPROP 2 LAST CDS_LIB mstr_standard
J 0
(-3325 3925);
DISPLAY 0.723404 (-3325 3925);
PAINT MONO (-3325 3925);
DISPLAY INVISIBLE (-3325 3925);
FORCEPROP 1 LAST BODY_TYPE PLUMBING
J 0
(-3325 3975);
DISPLAY 0.872340 (-3325 3975);
PAINT GREEN (-3325 3975);
DISPLAY INVISIBLE (-3325 3975);
FORCEPROP 1 LAST HDL_TAP TRUE
J 0
(-3000 3800);
DISPLAY 0.872340 (-3000 3800);
DISPLAY INVISIBLE (-3000 3800);
FORCEPROP 1 LAST PATH I201
J 0
(-3327 3925);
DISPLAY 0.872340 (-3327 3925);
PAINT GREEN (-3327 3925);
DISPLAY INVISIBLE (-3327 3925);
FORCEADD TAP..1
(-3325 3875);
FORCEPROP 3 LASTPIN (-3375 3875) SIG_NAME M_D_CPU1_SB_DQ<7>
J 0
(-3365 3885);
DISPLAY 0.659574 (-3365 3885);
PAINT MONO (-3365 3885);
DISPLAY INVISIBLE (-3365 3885);
FORCEPROP 1 LASTPIN (-3375 3875) BN 7
J 0
(-3387 3883);
DISPLAY 0.489362 (-3387 3883);
PAINT GREEN (-3387 3883);
FORCEPROP 2 LAST CDS_LIB mstr_standard
J 0
(-3325 3875);
DISPLAY 0.723404 (-3325 3875);
PAINT MONO (-3325 3875);
DISPLAY INVISIBLE (-3325 3875);
FORCEPROP 1 LAST BODY_TYPE PLUMBING
J 0
(-3325 3925);
DISPLAY 0.872340 (-3325 3925);
PAINT GREEN (-3325 3925);
DISPLAY INVISIBLE (-3325 3925);
FORCEPROP 1 LAST HDL_TAP TRUE
J 0
(-3000 3750);
DISPLAY 0.872340 (-3000 3750);
DISPLAY INVISIBLE (-3000 3750);
FORCEPROP 1 LAST PATH I202
J 0
(-3327 3875);
DISPLAY 0.872340 (-3327 3875);
PAINT GREEN (-3327 3875);
DISPLAY INVISIBLE (-3327 3875);
FORCEADD TAP..1
(-3325 3625);
FORCEPROP 3 LASTPIN (-3375 3625) SIG_NAME M_D_CPU1_SB_DQ<11>
J 0
(-3365 3635);
DISPLAY 0.659574 (-3365 3635);
PAINT MONO (-3365 3635);
DISPLAY INVISIBLE (-3365 3635);
FORCEPROP 1 LASTPIN (-3375 3625) BN 11
J 0
(-3387 3633);
DISPLAY 0.489362 (-3387 3633);
PAINT GREEN (-3387 3633);
FORCEPROP 2 LAST CDS_LIB mstr_standard
J 0
(-3325 3625);
DISPLAY 0.723404 (-3325 3625);
PAINT MONO (-3325 3625);
DISPLAY INVISIBLE (-3325 3625);
FORCEPROP 1 LAST BODY_TYPE PLUMBING
J 0
(-3325 3675);
DISPLAY 0.872340 (-3325 3675);
PAINT GREEN (-3325 3675);
DISPLAY INVISIBLE (-3325 3675);
FORCEPROP 1 LAST HDL_TAP TRUE
J 0
(-3000 3500);
DISPLAY 0.872340 (-3000 3500);
DISPLAY INVISIBLE (-3000 3500);
FORCEPROP 1 LAST PATH I203
J 0
(-3327 3625);
DISPLAY 0.872340 (-3327 3625);
PAINT GREEN (-3327 3625);
DISPLAY INVISIBLE (-3327 3625);
FORCEADD TAP..1
(-3325 3675);
FORCEPROP 3 LASTPIN (-3375 3675) SIG_NAME M_D_CPU1_SB_DQ<10>
J 0
(-3365 3685);
DISPLAY 0.659574 (-3365 3685);
PAINT MONO (-3365 3685);
DISPLAY INVISIBLE (-3365 3685);
FORCEPROP 1 LASTPIN (-3375 3675) BN 10
J 0
(-3387 3683);
DISPLAY 0.489362 (-3387 3683);
PAINT GREEN (-3387 3683);
FORCEPROP 2 LAST CDS_LIB mstr_standard
J 0
(-3325 3675);
DISPLAY 0.723404 (-3325 3675);
PAINT MONO (-3325 3675);
DISPLAY INVISIBLE (-3325 3675);
FORCEPROP 1 LAST BODY_TYPE PLUMBING
J 0
(-3325 3725);
DISPLAY 0.872340 (-3325 3725);
PAINT GREEN (-3325 3725);
DISPLAY INVISIBLE (-3325 3725);
FORCEPROP 1 LAST HDL_TAP TRUE
J 0
(-3000 3550);
DISPLAY 0.872340 (-3000 3550);
DISPLAY INVISIBLE (-3000 3550);
FORCEPROP 1 LAST PATH I204
J 0
(-3327 3675);
DISPLAY 0.872340 (-3327 3675);
PAINT GREEN (-3327 3675);
DISPLAY INVISIBLE (-3327 3675);
FORCEADD TAP..1
(-3325 3775);
FORCEPROP 3 LASTPIN (-3375 3775) SIG_NAME M_D_CPU1_SB_DQ<8>
J 0
(-3365 3785);
DISPLAY 0.659574 (-3365 3785);
PAINT MONO (-3365 3785);
DISPLAY INVISIBLE (-3365 3785);
FORCEPROP 1 LASTPIN (-3375 3775) BN 8
J 0
(-3387 3783);
DISPLAY 0.489362 (-3387 3783);
PAINT GREEN (-3387 3783);
FORCEPROP 2 LAST CDS_LIB mstr_standard
J 0
(-3325 3775);
DISPLAY 0.723404 (-3325 3775);
PAINT MONO (-3325 3775);
DISPLAY INVISIBLE (-3325 3775);
FORCEPROP 1 LAST BODY_TYPE PLUMBING
J 0
(-3325 3825);
DISPLAY 0.872340 (-3325 3825);
PAINT GREEN (-3325 3825);
DISPLAY INVISIBLE (-3325 3825);
FORCEPROP 1 LAST HDL_TAP TRUE
J 0
(-3000 3650);
DISPLAY 0.872340 (-3000 3650);
DISPLAY INVISIBLE (-3000 3650);
FORCEPROP 1 LAST PATH I205
J 0
(-3327 3775);
DISPLAY 0.872340 (-3327 3775);
PAINT GREEN (-3327 3775);
DISPLAY INVISIBLE (-3327 3775);
FORCEADD TAP..1
(-3325 3725);
FORCEPROP 3 LASTPIN (-3375 3725) SIG_NAME M_D_CPU1_SB_DQ<9>
J 0
(-3365 3735);
DISPLAY 0.659574 (-3365 3735);
PAINT MONO (-3365 3735);
DISPLAY INVISIBLE (-3365 3735);
FORCEPROP 1 LASTPIN (-3375 3725) BN 9
J 0
(-3387 3733);
DISPLAY 0.489362 (-3387 3733);
PAINT GREEN (-3387 3733);
FORCEPROP 2 LAST CDS_LIB mstr_standard
J 0
(-3325 3725);
DISPLAY 0.723404 (-3325 3725);
PAINT MONO (-3325 3725);
DISPLAY INVISIBLE (-3325 3725);
FORCEPROP 1 LAST BODY_TYPE PLUMBING
J 0
(-3325 3775);
DISPLAY 0.872340 (-3325 3775);
PAINT GREEN (-3325 3775);
DISPLAY INVISIBLE (-3325 3775);
FORCEPROP 1 LAST HDL_TAP TRUE
J 0
(-3000 3600);
DISPLAY 0.872340 (-3000 3600);
DISPLAY INVISIBLE (-3000 3600);
FORCEPROP 1 LAST PATH I206
J 0
(-3327 3725);
DISPLAY 0.872340 (-3327 3725);
PAINT GREEN (-3327 3725);
DISPLAY INVISIBLE (-3327 3725);
FORCEADD TAP..1
(-3325 3425);
FORCEPROP 3 LASTPIN (-3375 3425) SIG_NAME M_D_CPU1_SB_DQ<15>
J 0
(-3365 3435);
DISPLAY 0.659574 (-3365 3435);
PAINT MONO (-3365 3435);
DISPLAY INVISIBLE (-3365 3435);
FORCEPROP 1 LASTPIN (-3375 3425) BN 15
J 0
(-3387 3433);
DISPLAY 0.489362 (-3387 3433);
PAINT GREEN (-3387 3433);
FORCEPROP 2 LAST CDS_LIB mstr_standard
J 0
(-3325 3425);
DISPLAY 0.723404 (-3325 3425);
PAINT MONO (-3325 3425);
DISPLAY INVISIBLE (-3325 3425);
FORCEPROP 1 LAST BODY_TYPE PLUMBING
J 0
(-3325 3475);
DISPLAY 0.872340 (-3325 3475);
PAINT GREEN (-3325 3475);
DISPLAY INVISIBLE (-3325 3475);
FORCEPROP 1 LAST HDL_TAP TRUE
J 0
(-3000 3300);
DISPLAY 0.872340 (-3000 3300);
DISPLAY INVISIBLE (-3000 3300);
FORCEPROP 1 LAST PATH I207
J 0
(-3327 3425);
DISPLAY 0.872340 (-3327 3425);
PAINT GREEN (-3327 3425);
DISPLAY INVISIBLE (-3327 3425);
FORCEADD TAP..1
(-3325 3475);
FORCEPROP 3 LASTPIN (-3375 3475) SIG_NAME M_D_CPU1_SB_DQ<14>
J 0
(-3365 3485);
DISPLAY 0.659574 (-3365 3485);
PAINT MONO (-3365 3485);
DISPLAY INVISIBLE (-3365 3485);
FORCEPROP 1 LASTPIN (-3375 3475) BN 14
J 0
(-3387 3483);
DISPLAY 0.489362 (-3387 3483);
PAINT GREEN (-3387 3483);
FORCEPROP 2 LAST CDS_LIB mstr_standard
J 0
(-3325 3475);
DISPLAY 0.723404 (-3325 3475);
PAINT MONO (-3325 3475);
DISPLAY INVISIBLE (-3325 3475);
FORCEPROP 1 LAST BODY_TYPE PLUMBING
J 0
(-3325 3525);
DISPLAY 0.872340 (-3325 3525);
PAINT GREEN (-3325 3525);
DISPLAY INVISIBLE (-3325 3525);
FORCEPROP 1 LAST HDL_TAP TRUE
J 0
(-3000 3350);
DISPLAY 0.872340 (-3000 3350);
DISPLAY INVISIBLE (-3000 3350);
FORCEPROP 1 LAST PATH I208
J 0
(-3327 3475);
DISPLAY 0.872340 (-3327 3475);
PAINT GREEN (-3327 3475);
DISPLAY INVISIBLE (-3327 3475);
FORCEADD TAP..1
(-3325 3575);
FORCEPROP 3 LASTPIN (-3375 3575) SIG_NAME M_D_CPU1_SB_DQ<12>
J 0
(-3365 3585);
DISPLAY 0.659574 (-3365 3585);
PAINT MONO (-3365 3585);
DISPLAY INVISIBLE (-3365 3585);
FORCEPROP 1 LASTPIN (-3375 3575) BN 12
J 0
(-3387 3583);
DISPLAY 0.489362 (-3387 3583);
PAINT GREEN (-3387 3583);
FORCEPROP 2 LAST CDS_LIB mstr_standard
J 0
(-3325 3575);
DISPLAY 0.723404 (-3325 3575);
PAINT MONO (-3325 3575);
DISPLAY INVISIBLE (-3325 3575);
FORCEPROP 1 LAST BODY_TYPE PLUMBING
J 0
(-3325 3625);
DISPLAY 0.872340 (-3325 3625);
PAINT GREEN (-3325 3625);
DISPLAY INVISIBLE (-3325 3625);
FORCEPROP 1 LAST HDL_TAP TRUE
J 0
(-3000 3450);
DISPLAY 0.872340 (-3000 3450);
DISPLAY INVISIBLE (-3000 3450);
FORCEPROP 1 LAST PATH I209
J 0
(-3327 3575);
DISPLAY 0.872340 (-3327 3575);
PAINT GREEN (-3327 3575);
DISPLAY INVISIBLE (-3327 3575);
FORCEADD TAP..1
(-3325 3525);
FORCEPROP 3 LASTPIN (-3375 3525) SIG_NAME M_D_CPU1_SB_DQ<13>
J 0
(-3365 3535);
DISPLAY 0.659574 (-3365 3535);
PAINT MONO (-3365 3535);
DISPLAY INVISIBLE (-3365 3535);
FORCEPROP 1 LASTPIN (-3375 3525) BN 13
J 0
(-3387 3533);
DISPLAY 0.489362 (-3387 3533);
PAINT GREEN (-3387 3533);
FORCEPROP 2 LAST CDS_LIB mstr_standard
J 0
(-3325 3525);
DISPLAY 0.723404 (-3325 3525);
PAINT MONO (-3325 3525);
DISPLAY INVISIBLE (-3325 3525);
FORCEPROP 1 LAST BODY_TYPE PLUMBING
J 0
(-3325 3575);
DISPLAY 0.872340 (-3325 3575);
PAINT GREEN (-3325 3575);
DISPLAY INVISIBLE (-3325 3575);
FORCEPROP 1 LAST HDL_TAP TRUE
J 0
(-3000 3400);
DISPLAY 0.872340 (-3000 3400);
DISPLAY INVISIBLE (-3000 3400);
FORCEPROP 1 LAST PATH I210
J 0
(-3327 3525);
DISPLAY 0.872340 (-3327 3525);
PAINT GREEN (-3327 3525);
DISPLAY INVISIBLE (-3327 3525);
FORCEADD TAP..1
(-3325 3325);
FORCEPROP 3 LASTPIN (-3375 3325) SIG_NAME M_D_CPU1_SB_DQ<16>
J 0
(-3365 3335);
DISPLAY 0.659574 (-3365 3335);
PAINT MONO (-3365 3335);
DISPLAY INVISIBLE (-3365 3335);
FORCEPROP 1 LASTPIN (-3375 3325) BN 16
J 0
(-3387 3333);
DISPLAY 0.489362 (-3387 3333);
PAINT GREEN (-3387 3333);
FORCEPROP 2 LAST CDS_LIB mstr_standard
J 0
(-3325 3325);
DISPLAY 0.723404 (-3325 3325);
PAINT MONO (-3325 3325);
DISPLAY INVISIBLE (-3325 3325);
FORCEPROP 1 LAST BODY_TYPE PLUMBING
J 0
(-3325 3375);
DISPLAY 0.872340 (-3325 3375);
PAINT GREEN (-3325 3375);
DISPLAY INVISIBLE (-3325 3375);
FORCEPROP 1 LAST HDL_TAP TRUE
J 0
(-3000 3200);
DISPLAY 0.872340 (-3000 3200);
DISPLAY INVISIBLE (-3000 3200);
FORCEPROP 1 LAST PATH I211
J 0
(-3327 3325);
DISPLAY 0.872340 (-3327 3325);
PAINT GREEN (-3327 3325);
DISPLAY INVISIBLE (-3327 3325);
FORCEADD TAP..1
(-3325 3275);
FORCEPROP 3 LASTPIN (-3375 3275) SIG_NAME M_D_CPU1_SB_DQ<17>
J 0
(-3365 3285);
DISPLAY 0.659574 (-3365 3285);
PAINT MONO (-3365 3285);
DISPLAY INVISIBLE (-3365 3285);
FORCEPROP 1 LASTPIN (-3375 3275) BN 17
J 0
(-3387 3283);
DISPLAY 0.489362 (-3387 3283);
PAINT GREEN (-3387 3283);
FORCEPROP 2 LAST CDS_LIB mstr_standard
J 0
(-3325 3275);
DISPLAY 0.723404 (-3325 3275);
PAINT MONO (-3325 3275);
DISPLAY INVISIBLE (-3325 3275);
FORCEPROP 1 LAST BODY_TYPE PLUMBING
J 0
(-3325 3325);
DISPLAY 0.872340 (-3325 3325);
PAINT GREEN (-3325 3325);
DISPLAY INVISIBLE (-3325 3325);
FORCEPROP 1 LAST HDL_TAP TRUE
J 0
(-3000 3150);
DISPLAY 0.872340 (-3000 3150);
DISPLAY INVISIBLE (-3000 3150);
FORCEPROP 1 LAST PATH I212
J 0
(-3327 3275);
DISPLAY 0.872340 (-3327 3275);
PAINT GREEN (-3327 3275);
DISPLAY INVISIBLE (-3327 3275);
FORCEADD TAP..1
(-3325 3225);
FORCEPROP 3 LASTPIN (-3375 3225) SIG_NAME M_D_CPU1_SB_DQ<18>
J 0
(-3365 3235);
DISPLAY 0.659574 (-3365 3235);
PAINT MONO (-3365 3235);
DISPLAY INVISIBLE (-3365 3235);
FORCEPROP 1 LASTPIN (-3375 3225) BN 18
J 0
(-3387 3233);
DISPLAY 0.489362 (-3387 3233);
PAINT GREEN (-3387 3233);
FORCEPROP 2 LAST CDS_LIB mstr_standard
J 0
(-3325 3225);
DISPLAY 0.723404 (-3325 3225);
PAINT MONO (-3325 3225);
DISPLAY INVISIBLE (-3325 3225);
FORCEPROP 1 LAST BODY_TYPE PLUMBING
J 0
(-3325 3275);
DISPLAY 0.872340 (-3325 3275);
PAINT GREEN (-3325 3275);
DISPLAY INVISIBLE (-3325 3275);
FORCEPROP 1 LAST HDL_TAP TRUE
J 0
(-3000 3100);
DISPLAY 0.872340 (-3000 3100);
DISPLAY INVISIBLE (-3000 3100);
FORCEPROP 1 LAST PATH I213
J 0
(-3327 3225);
DISPLAY 0.872340 (-3327 3225);
PAINT GREEN (-3327 3225);
DISPLAY INVISIBLE (-3327 3225);
FORCEADD TAP..1
(-3325 3075);
FORCEPROP 3 LASTPIN (-3375 3075) SIG_NAME M_D_CPU1_SB_DQ<21>
J 0
(-3365 3085);
DISPLAY 0.659574 (-3365 3085);
PAINT MONO (-3365 3085);
DISPLAY INVISIBLE (-3365 3085);
FORCEPROP 1 LASTPIN (-3375 3075) BN 21
J 0
(-3387 3083);
DISPLAY 0.489362 (-3387 3083);
PAINT GREEN (-3387 3083);
FORCEPROP 2 LAST CDS_LIB mstr_standard
J 0
(-3325 3075);
DISPLAY 0.723404 (-3325 3075);
PAINT MONO (-3325 3075);
DISPLAY INVISIBLE (-3325 3075);
FORCEPROP 1 LAST BODY_TYPE PLUMBING
J 0
(-3325 3125);
DISPLAY 0.872340 (-3325 3125);
PAINT GREEN (-3325 3125);
DISPLAY INVISIBLE (-3325 3125);
FORCEPROP 1 LAST HDL_TAP TRUE
J 0
(-3000 2950);
DISPLAY 0.872340 (-3000 2950);
DISPLAY INVISIBLE (-3000 2950);
FORCEPROP 1 LAST PATH I214
J 0
(-3327 3075);
DISPLAY 0.872340 (-3327 3075);
PAINT GREEN (-3327 3075);
DISPLAY INVISIBLE (-3327 3075);
FORCEADD TAP..1
(-3325 3175);
FORCEPROP 3 LASTPIN (-3375 3175) SIG_NAME M_D_CPU1_SB_DQ<19>
J 0
(-3365 3185);
DISPLAY 0.659574 (-3365 3185);
PAINT MONO (-3365 3185);
DISPLAY INVISIBLE (-3365 3185);
FORCEPROP 1 LASTPIN (-3375 3175) BN 19
J 0
(-3387 3183);
DISPLAY 0.489362 (-3387 3183);
PAINT GREEN (-3387 3183);
FORCEPROP 2 LAST CDS_LIB mstr_standard
J 0
(-3325 3175);
DISPLAY 0.723404 (-3325 3175);
PAINT MONO (-3325 3175);
DISPLAY INVISIBLE (-3325 3175);
FORCEPROP 1 LAST BODY_TYPE PLUMBING
J 0
(-3325 3225);
DISPLAY 0.872340 (-3325 3225);
PAINT GREEN (-3325 3225);
DISPLAY INVISIBLE (-3325 3225);
FORCEPROP 1 LAST HDL_TAP TRUE
J 0
(-3000 3050);
DISPLAY 0.872340 (-3000 3050);
DISPLAY INVISIBLE (-3000 3050);
FORCEPROP 1 LAST PATH I215
J 0
(-3327 3175);
DISPLAY 0.872340 (-3327 3175);
PAINT GREEN (-3327 3175);
DISPLAY INVISIBLE (-3327 3175);
FORCEADD TAP..1
(-3325 3125);
FORCEPROP 3 LASTPIN (-3375 3125) SIG_NAME M_D_CPU1_SB_DQ<20>
J 0
(-3365 3135);
DISPLAY 0.659574 (-3365 3135);
PAINT MONO (-3365 3135);
DISPLAY INVISIBLE (-3365 3135);
FORCEPROP 1 LASTPIN (-3375 3125) BN 20
J 0
(-3387 3133);
DISPLAY 0.489362 (-3387 3133);
PAINT GREEN (-3387 3133);
FORCEPROP 2 LAST CDS_LIB mstr_standard
J 0
(-3325 3125);
DISPLAY 0.723404 (-3325 3125);
PAINT MONO (-3325 3125);
DISPLAY INVISIBLE (-3325 3125);
FORCEPROP 1 LAST BODY_TYPE PLUMBING
J 0
(-3325 3175);
DISPLAY 0.872340 (-3325 3175);
PAINT GREEN (-3325 3175);
DISPLAY INVISIBLE (-3325 3175);
FORCEPROP 1 LAST HDL_TAP TRUE
J 0
(-3000 3000);
DISPLAY 0.872340 (-3000 3000);
DISPLAY INVISIBLE (-3000 3000);
FORCEPROP 1 LAST PATH I216
J 0
(-3327 3125);
DISPLAY 0.872340 (-3327 3125);
PAINT GREEN (-3327 3125);
DISPLAY INVISIBLE (-3327 3125);
FORCEADD TAP..1
(-3325 2875);
FORCEPROP 3 LASTPIN (-3375 2875) SIG_NAME M_D_CPU1_SB_DQ<24>
J 0
(-3365 2885);
DISPLAY 0.659574 (-3365 2885);
PAINT MONO (-3365 2885);
DISPLAY INVISIBLE (-3365 2885);
FORCEPROP 1 LASTPIN (-3375 2875) BN 24
J 0
(-3387 2883);
DISPLAY 0.489362 (-3387 2883);
PAINT GREEN (-3387 2883);
FORCEPROP 2 LAST CDS_LIB mstr_standard
J 0
(-3325 2875);
DISPLAY 0.723404 (-3325 2875);
PAINT MONO (-3325 2875);
DISPLAY INVISIBLE (-3325 2875);
FORCEPROP 1 LAST BODY_TYPE PLUMBING
J 0
(-3325 2925);
DISPLAY 0.872340 (-3325 2925);
PAINT GREEN (-3325 2925);
DISPLAY INVISIBLE (-3325 2925);
FORCEPROP 1 LAST HDL_TAP TRUE
J 0
(-3000 2750);
DISPLAY 0.872340 (-3000 2750);
DISPLAY INVISIBLE (-3000 2750);
FORCEPROP 1 LAST PATH I217
J 0
(-3327 2875);
DISPLAY 0.872340 (-3327 2875);
PAINT GREEN (-3327 2875);
DISPLAY INVISIBLE (-3327 2875);
FORCEADD TAP..1
(-3325 2975);
FORCEPROP 3 LASTPIN (-3375 2975) SIG_NAME M_D_CPU1_SB_DQ<23>
J 0
(-3365 2985);
DISPLAY 0.659574 (-3365 2985);
PAINT MONO (-3365 2985);
DISPLAY INVISIBLE (-3365 2985);
FORCEPROP 1 LASTPIN (-3375 2975) BN 23
J 0
(-3387 2983);
DISPLAY 0.489362 (-3387 2983);
PAINT GREEN (-3387 2983);
FORCEPROP 2 LAST CDS_LIB mstr_standard
J 0
(-3325 2975);
DISPLAY 0.723404 (-3325 2975);
PAINT MONO (-3325 2975);
DISPLAY INVISIBLE (-3325 2975);
FORCEPROP 1 LAST BODY_TYPE PLUMBING
J 0
(-3325 3025);
DISPLAY 0.872340 (-3325 3025);
PAINT GREEN (-3325 3025);
DISPLAY INVISIBLE (-3325 3025);
FORCEPROP 1 LAST HDL_TAP TRUE
J 0
(-3000 2850);
DISPLAY 0.872340 (-3000 2850);
DISPLAY INVISIBLE (-3000 2850);
FORCEPROP 1 LAST PATH I218
J 0
(-3327 2975);
DISPLAY 0.872340 (-3327 2975);
PAINT GREEN (-3327 2975);
DISPLAY INVISIBLE (-3327 2975);
FORCEADD TAP..1
(-3325 3025);
FORCEPROP 3 LASTPIN (-3375 3025) SIG_NAME M_D_CPU1_SB_DQ<22>
J 0
(-3365 3035);
DISPLAY 0.659574 (-3365 3035);
PAINT MONO (-3365 3035);
DISPLAY INVISIBLE (-3365 3035);
FORCEPROP 1 LASTPIN (-3375 3025) BN 22
J 0
(-3387 3033);
DISPLAY 0.489362 (-3387 3033);
PAINT GREEN (-3387 3033);
FORCEPROP 2 LAST CDS_LIB mstr_standard
J 0
(-3325 3025);
DISPLAY 0.723404 (-3325 3025);
PAINT MONO (-3325 3025);
DISPLAY INVISIBLE (-3325 3025);
FORCEPROP 1 LAST BODY_TYPE PLUMBING
J 0
(-3325 3075);
DISPLAY 0.872340 (-3325 3075);
PAINT GREEN (-3325 3075);
DISPLAY INVISIBLE (-3325 3075);
FORCEPROP 1 LAST HDL_TAP TRUE
J 0
(-3000 2900);
DISPLAY 0.872340 (-3000 2900);
DISPLAY INVISIBLE (-3000 2900);
FORCEPROP 1 LAST PATH I219
J 0
(-3327 3025);
DISPLAY 0.872340 (-3327 3025);
PAINT GREEN (-3327 3025);
DISPLAY INVISIBLE (-3327 3025);
FORCEADD TAP..1
(-3325 2825);
FORCEPROP 3 LASTPIN (-3375 2825) SIG_NAME M_D_CPU1_SB_DQ<25>
J 0
(-3365 2835);
DISPLAY 0.659574 (-3365 2835);
PAINT MONO (-3365 2835);
DISPLAY INVISIBLE (-3365 2835);
FORCEPROP 1 LASTPIN (-3375 2825) BN 25
J 0
(-3387 2833);
DISPLAY 0.489362 (-3387 2833);
PAINT GREEN (-3387 2833);
FORCEPROP 2 LAST CDS_LIB mstr_standard
J 0
(-3325 2825);
DISPLAY 0.723404 (-3325 2825);
PAINT MONO (-3325 2825);
DISPLAY INVISIBLE (-3325 2825);
FORCEPROP 1 LAST BODY_TYPE PLUMBING
J 0
(-3325 2875);
DISPLAY 0.872340 (-3325 2875);
PAINT GREEN (-3325 2875);
DISPLAY INVISIBLE (-3325 2875);
FORCEPROP 1 LAST HDL_TAP TRUE
J 0
(-3000 2700);
DISPLAY 0.872340 (-3000 2700);
DISPLAY INVISIBLE (-3000 2700);
FORCEPROP 1 LAST PATH I220
J 0
(-3327 2825);
DISPLAY 0.872340 (-3327 2825);
PAINT GREEN (-3327 2825);
DISPLAY INVISIBLE (-3327 2825);
FORCEADD TAP..1
(-3325 2625);
FORCEPROP 3 LASTPIN (-3375 2625) SIG_NAME M_D_CPU1_SB_DQ<29>
J 0
(-3365 2635);
DISPLAY 0.659574 (-3365 2635);
PAINT MONO (-3365 2635);
DISPLAY INVISIBLE (-3365 2635);
FORCEPROP 1 LASTPIN (-3375 2625) BN 29
J 0
(-3387 2633);
DISPLAY 0.489362 (-3387 2633);
PAINT GREEN (-3387 2633);
FORCEPROP 2 LAST CDS_LIB mstr_standard
J 0
(-3325 2625);
DISPLAY 0.723404 (-3325 2625);
PAINT MONO (-3325 2625);
DISPLAY INVISIBLE (-3325 2625);
FORCEPROP 1 LAST BODY_TYPE PLUMBING
J 0
(-3325 2675);
DISPLAY 0.872340 (-3325 2675);
PAINT GREEN (-3325 2675);
DISPLAY INVISIBLE (-3325 2675);
FORCEPROP 1 LAST HDL_TAP TRUE
J 0
(-3000 2500);
DISPLAY 0.872340 (-3000 2500);
DISPLAY INVISIBLE (-3000 2500);
FORCEPROP 1 LAST PATH I221
J 0
(-3327 2625);
DISPLAY 0.872340 (-3327 2625);
PAINT GREEN (-3327 2625);
DISPLAY INVISIBLE (-3327 2625);
FORCEADD TAP..1
(-3325 2575);
FORCEPROP 3 LASTPIN (-3375 2575) SIG_NAME M_D_CPU1_SB_DQ<30>
J 0
(-3365 2585);
DISPLAY 0.659574 (-3365 2585);
PAINT MONO (-3365 2585);
DISPLAY INVISIBLE (-3365 2585);
FORCEPROP 1 LASTPIN (-3375 2575) BN 30
J 0
(-3387 2583);
DISPLAY 0.489362 (-3387 2583);
PAINT GREEN (-3387 2583);
FORCEPROP 2 LAST CDS_LIB mstr_standard
J 0
(-3325 2575);
DISPLAY 0.723404 (-3325 2575);
PAINT MONO (-3325 2575);
DISPLAY INVISIBLE (-3325 2575);
FORCEPROP 1 LAST BODY_TYPE PLUMBING
J 0
(-3325 2625);
DISPLAY 0.872340 (-3325 2625);
PAINT GREEN (-3325 2625);
DISPLAY INVISIBLE (-3325 2625);
FORCEPROP 1 LAST HDL_TAP TRUE
J 0
(-3000 2450);
DISPLAY 0.872340 (-3000 2450);
DISPLAY INVISIBLE (-3000 2450);
FORCEPROP 1 LAST PATH I222
J 0
(-3327 2575);
DISPLAY 0.872340 (-3327 2575);
PAINT GREEN (-3327 2575);
DISPLAY INVISIBLE (-3327 2575);
FORCEADD TAP..1
(-3325 2675);
FORCEPROP 3 LASTPIN (-3375 2675) SIG_NAME M_D_CPU1_SB_DQ<28>
J 0
(-3365 2685);
DISPLAY 0.659574 (-3365 2685);
PAINT MONO (-3365 2685);
DISPLAY INVISIBLE (-3365 2685);
FORCEPROP 1 LASTPIN (-3375 2675) BN 28
J 0
(-3387 2683);
DISPLAY 0.489362 (-3387 2683);
PAINT GREEN (-3387 2683);
FORCEPROP 2 LAST CDS_LIB mstr_standard
J 0
(-3325 2675);
DISPLAY 0.723404 (-3325 2675);
PAINT MONO (-3325 2675);
DISPLAY INVISIBLE (-3325 2675);
FORCEPROP 1 LAST BODY_TYPE PLUMBING
J 0
(-3325 2725);
DISPLAY 0.872340 (-3325 2725);
PAINT GREEN (-3325 2725);
DISPLAY INVISIBLE (-3325 2725);
FORCEPROP 1 LAST HDL_TAP TRUE
J 0
(-3000 2550);
DISPLAY 0.872340 (-3000 2550);
DISPLAY INVISIBLE (-3000 2550);
FORCEPROP 1 LAST PATH I223
J 0
(-3327 2675);
DISPLAY 0.872340 (-3327 2675);
PAINT GREEN (-3327 2675);
DISPLAY INVISIBLE (-3327 2675);
FORCEADD TAP..1
(-3325 2775);
FORCEPROP 3 LASTPIN (-3375 2775) SIG_NAME M_D_CPU1_SB_DQ<26>
J 0
(-3365 2785);
DISPLAY 0.659574 (-3365 2785);
PAINT MONO (-3365 2785);
DISPLAY INVISIBLE (-3365 2785);
FORCEPROP 1 LASTPIN (-3375 2775) BN 26
J 0
(-3387 2783);
DISPLAY 0.489362 (-3387 2783);
PAINT GREEN (-3387 2783);
FORCEPROP 2 LAST CDS_LIB mstr_standard
J 0
(-3325 2775);
DISPLAY 0.723404 (-3325 2775);
PAINT MONO (-3325 2775);
DISPLAY INVISIBLE (-3325 2775);
FORCEPROP 1 LAST BODY_TYPE PLUMBING
J 0
(-3325 2825);
DISPLAY 0.872340 (-3325 2825);
PAINT GREEN (-3325 2825);
DISPLAY INVISIBLE (-3325 2825);
FORCEPROP 1 LAST HDL_TAP TRUE
J 0
(-3000 2650);
DISPLAY 0.872340 (-3000 2650);
DISPLAY INVISIBLE (-3000 2650);
FORCEPROP 1 LAST PATH I224
J 0
(-3327 2775);
DISPLAY 0.872340 (-3327 2775);
PAINT GREEN (-3327 2775);
DISPLAY INVISIBLE (-3327 2775);
FORCEADD TAP..1
(-3325 2725);
FORCEPROP 3 LASTPIN (-3375 2725) SIG_NAME M_D_CPU1_SB_DQ<27>
J 0
(-3365 2735);
DISPLAY 0.659574 (-3365 2735);
PAINT MONO (-3365 2735);
DISPLAY INVISIBLE (-3365 2735);
FORCEPROP 1 LASTPIN (-3375 2725) BN 27
J 0
(-3387 2733);
DISPLAY 0.489362 (-3387 2733);
PAINT GREEN (-3387 2733);
FORCEPROP 2 LAST CDS_LIB mstr_standard
J 0
(-3325 2725);
DISPLAY 0.723404 (-3325 2725);
PAINT MONO (-3325 2725);
DISPLAY INVISIBLE (-3325 2725);
FORCEPROP 1 LAST BODY_TYPE PLUMBING
J 0
(-3325 2775);
DISPLAY 0.872340 (-3325 2775);
PAINT GREEN (-3325 2775);
DISPLAY INVISIBLE (-3325 2775);
FORCEPROP 1 LAST HDL_TAP TRUE
J 0
(-3000 2600);
DISPLAY 0.872340 (-3000 2600);
DISPLAY INVISIBLE (-3000 2600);
FORCEPROP 1 LAST PATH I225
J 0
(-3327 2725);
DISPLAY 0.872340 (-3327 2725);
PAINT GREEN (-3327 2725);
DISPLAY INVISIBLE (-3327 2725);
FORCEADD TAP..1
(-3325 2525);
FORCEPROP 3 LASTPIN (-3375 2525) SIG_NAME M_D_CPU1_SB_DQ<31>
J 0
(-3365 2535);
DISPLAY 0.659574 (-3365 2535);
PAINT MONO (-3365 2535);
DISPLAY INVISIBLE (-3365 2535);
FORCEPROP 1 LASTPIN (-3375 2525) BN 31
J 0
(-3387 2533);
DISPLAY 0.489362 (-3387 2533);
PAINT GREEN (-3387 2533);
FORCEPROP 2 LAST CDS_LIB mstr_standard
J 0
(-3325 2525);
DISPLAY 0.723404 (-3325 2525);
PAINT MONO (-3325 2525);
DISPLAY INVISIBLE (-3325 2525);
FORCEPROP 1 LAST BODY_TYPE PLUMBING
J 0
(-3325 2575);
DISPLAY 0.872340 (-3325 2575);
PAINT GREEN (-3325 2575);
DISPLAY INVISIBLE (-3325 2575);
FORCEPROP 1 LAST HDL_TAP TRUE
J 0
(-3000 2400);
DISPLAY 0.872340 (-3000 2400);
DISPLAY INVISIBLE (-3000 2400);
FORCEPROP 1 LAST PATH I226
J 0
(-3327 2525);
DISPLAY 0.872340 (-3327 2525);
PAINT GREEN (-3327 2525);
DISPLAY INVISIBLE (-3327 2525);
FORCEADD TAP..1
(-3325 2425);
FORCEPROP 3 LASTPIN (-3375 2425) SIG_NAME M_D_CPU1_SA_CB<0>
J 0
(-3365 2435);
DISPLAY 0.659574 (-3365 2435);
PAINT MONO (-3365 2435);
DISPLAY INVISIBLE (-3365 2435);
FORCEPROP 1 LASTPIN (-3375 2425) BN 0
J 0
(-3387 2433);
DISPLAY 0.489362 (-3387 2433);
PAINT GREEN (-3387 2433);
FORCEPROP 2 LAST CDS_LIB mstr_standard
J 2
(-3325 2425);
DISPLAY 0.723404 (-3325 2425);
PAINT MONO (-3325 2425);
DISPLAY INVISIBLE (-3325 2425);
FORCEPROP 1 LAST BODY_TYPE PLUMBING
J 0
(-3325 2475);
DISPLAY 0.872340 (-3325 2475);
PAINT GREEN (-3325 2475);
DISPLAY INVISIBLE (-3325 2475);
FORCEPROP 1 LAST HDL_TAP TRUE
J 0
(-3000 2300);
DISPLAY 0.872340 (-3000 2300);
DISPLAY INVISIBLE (-3000 2300);
FORCEPROP 1 LAST PATH I227
J 0
(-3327 2425);
DISPLAY 0.872340 (-3327 2425);
PAINT GREEN (-3327 2425);
DISPLAY INVISIBLE (-3327 2425);
FORCEADD TAP..1
(-3325 2325);
FORCEPROP 3 LASTPIN (-3375 2325) SIG_NAME M_D_CPU1_SA_CB<2>
J 0
(-3365 2335);
DISPLAY 0.659574 (-3365 2335);
PAINT MONO (-3365 2335);
DISPLAY INVISIBLE (-3365 2335);
FORCEPROP 1 LASTPIN (-3375 2325) BN 2
J 0
(-3387 2333);
DISPLAY 0.489362 (-3387 2333);
PAINT GREEN (-3387 2333);
FORCEPROP 2 LAST CDS_LIB mstr_standard
J 2
(-3325 2325);
DISPLAY 0.723404 (-3325 2325);
PAINT MONO (-3325 2325);
DISPLAY INVISIBLE (-3325 2325);
FORCEPROP 1 LAST BODY_TYPE PLUMBING
J 0
(-3325 2375);
DISPLAY 0.872340 (-3325 2375);
PAINT GREEN (-3325 2375);
DISPLAY INVISIBLE (-3325 2375);
FORCEPROP 1 LAST HDL_TAP TRUE
J 0
(-3000 2200);
DISPLAY 0.872340 (-3000 2200);
DISPLAY INVISIBLE (-3000 2200);
FORCEPROP 1 LAST PATH I228
J 0
(-3327 2325);
DISPLAY 0.872340 (-3327 2325);
PAINT GREEN (-3327 2325);
DISPLAY INVISIBLE (-3327 2325);
FORCEADD TAP..1
(-3325 2375);
FORCEPROP 3 LASTPIN (-3375 2375) SIG_NAME M_D_CPU1_SA_CB<1>
J 0
(-3365 2385);
DISPLAY 0.659574 (-3365 2385);
PAINT MONO (-3365 2385);
DISPLAY INVISIBLE (-3365 2385);
FORCEPROP 1 LASTPIN (-3375 2375) BN 1
J 0
(-3387 2383);
DISPLAY 0.489362 (-3387 2383);
PAINT GREEN (-3387 2383);
FORCEPROP 2 LAST CDS_LIB mstr_standard
J 2
(-3325 2375);
DISPLAY 0.723404 (-3325 2375);
PAINT MONO (-3325 2375);
DISPLAY INVISIBLE (-3325 2375);
FORCEPROP 1 LAST BODY_TYPE PLUMBING
J 0
(-3325 2425);
DISPLAY 0.872340 (-3325 2425);
PAINT GREEN (-3325 2425);
DISPLAY INVISIBLE (-3325 2425);
FORCEPROP 1 LAST HDL_TAP TRUE
J 0
(-3000 2250);
DISPLAY 0.872340 (-3000 2250);
DISPLAY INVISIBLE (-3000 2250);
FORCEPROP 1 LAST PATH I229
J 0
(-3327 2375);
DISPLAY 0.872340 (-3327 2375);
PAINT GREEN (-3327 2375);
DISPLAY INVISIBLE (-3327 2375);
FORCEADD TAP..1
(-3325 2275);
FORCEPROP 3 LASTPIN (-3375 2275) SIG_NAME M_D_CPU1_SA_CB<3>
J 0
(-3365 2285);
DISPLAY 0.659574 (-3365 2285);
PAINT MONO (-3365 2285);
DISPLAY INVISIBLE (-3365 2285);
FORCEPROP 1 LASTPIN (-3375 2275) BN 3
J 0
(-3387 2283);
DISPLAY 0.489362 (-3387 2283);
PAINT GREEN (-3387 2283);
FORCEPROP 2 LAST CDS_LIB mstr_standard
J 2
(-3325 2275);
DISPLAY 0.723404 (-3325 2275);
PAINT MONO (-3325 2275);
DISPLAY INVISIBLE (-3325 2275);
FORCEPROP 1 LAST BODY_TYPE PLUMBING
J 0
(-3325 2325);
DISPLAY 0.872340 (-3325 2325);
PAINT GREEN (-3325 2325);
DISPLAY INVISIBLE (-3325 2325);
FORCEPROP 1 LAST HDL_TAP TRUE
J 0
(-3000 2150);
DISPLAY 0.872340 (-3000 2150);
DISPLAY INVISIBLE (-3000 2150);
FORCEPROP 1 LAST PATH I230
J 0
(-3327 2275);
DISPLAY 0.872340 (-3327 2275);
PAINT GREEN (-3327 2275);
DISPLAY INVISIBLE (-3327 2275);
FORCEADD TAP..1
(-3325 2225);
FORCEPROP 3 LASTPIN (-3375 2225) SIG_NAME M_D_CPU1_SA_CB<4>
J 0
(-3365 2235);
DISPLAY 0.659574 (-3365 2235);
PAINT MONO (-3365 2235);
DISPLAY INVISIBLE (-3365 2235);
FORCEPROP 1 LASTPIN (-3375 2225) BN 4
J 0
(-3387 2233);
DISPLAY 0.489362 (-3387 2233);
PAINT GREEN (-3387 2233);
FORCEPROP 2 LAST CDS_LIB mstr_standard
J 2
(-3325 2225);
DISPLAY 0.723404 (-3325 2225);
PAINT MONO (-3325 2225);
DISPLAY INVISIBLE (-3325 2225);
FORCEPROP 1 LAST BODY_TYPE PLUMBING
J 0
(-3325 2275);
DISPLAY 0.872340 (-3325 2275);
PAINT GREEN (-3325 2275);
DISPLAY INVISIBLE (-3325 2275);
FORCEPROP 1 LAST HDL_TAP TRUE
J 0
(-3000 2100);
DISPLAY 0.872340 (-3000 2100);
DISPLAY INVISIBLE (-3000 2100);
FORCEPROP 1 LAST PATH I231
J 0
(-3327 2225);
DISPLAY 0.872340 (-3327 2225);
PAINT GREEN (-3327 2225);
DISPLAY INVISIBLE (-3327 2225);
FORCEADD TAP..1
(-3325 2175);
FORCEPROP 3 LASTPIN (-3375 2175) SIG_NAME M_D_CPU1_SA_CB<5>
J 0
(-3365 2185);
DISPLAY 0.659574 (-3365 2185);
PAINT MONO (-3365 2185);
DISPLAY INVISIBLE (-3365 2185);
FORCEPROP 1 LASTPIN (-3375 2175) BN 5
J 0
(-3387 2183);
DISPLAY 0.489362 (-3387 2183);
PAINT GREEN (-3387 2183);
FORCEPROP 2 LAST CDS_LIB mstr_standard
J 2
(-3325 2175);
DISPLAY 0.723404 (-3325 2175);
PAINT MONO (-3325 2175);
DISPLAY INVISIBLE (-3325 2175);
FORCEPROP 1 LAST BODY_TYPE PLUMBING
J 0
(-3325 2225);
DISPLAY 0.872340 (-3325 2225);
PAINT GREEN (-3325 2225);
DISPLAY INVISIBLE (-3325 2225);
FORCEPROP 1 LAST HDL_TAP TRUE
J 0
(-3000 2050);
DISPLAY 0.872340 (-3000 2050);
DISPLAY INVISIBLE (-3000 2050);
FORCEPROP 1 LAST PATH I232
J 0
(-3327 2175);
DISPLAY 0.872340 (-3327 2175);
PAINT GREEN (-3327 2175);
DISPLAY INVISIBLE (-3327 2175);
FORCEADD TAP..1
(-3325 2125);
FORCEPROP 3 LASTPIN (-3375 2125) SIG_NAME M_D_CPU1_SA_CB<6>
J 0
(-3365 2135);
DISPLAY 0.659574 (-3365 2135);
PAINT MONO (-3365 2135);
DISPLAY INVISIBLE (-3365 2135);
FORCEPROP 1 LASTPIN (-3375 2125) BN 6
J 0
(-3387 2133);
DISPLAY 0.489362 (-3387 2133);
PAINT GREEN (-3387 2133);
FORCEPROP 2 LAST CDS_LIB mstr_standard
J 2
(-3325 2125);
DISPLAY 0.723404 (-3325 2125);
PAINT MONO (-3325 2125);
DISPLAY INVISIBLE (-3325 2125);
FORCEPROP 1 LAST BODY_TYPE PLUMBING
J 0
(-3325 2175);
DISPLAY 0.872340 (-3325 2175);
PAINT GREEN (-3325 2175);
DISPLAY INVISIBLE (-3325 2175);
FORCEPROP 1 LAST HDL_TAP TRUE
J 0
(-3000 2000);
DISPLAY 0.872340 (-3000 2000);
DISPLAY INVISIBLE (-3000 2000);
FORCEPROP 1 LAST PATH I233
J 0
(-3327 2125);
DISPLAY 0.872340 (-3327 2125);
PAINT GREEN (-3327 2125);
DISPLAY INVISIBLE (-3327 2125);
FORCEADD TAP..1
(-3325 2075);
FORCEPROP 3 LASTPIN (-3375 2075) SIG_NAME M_D_CPU1_SA_CB<7>
J 0
(-3365 2085);
DISPLAY 0.659574 (-3365 2085);
PAINT MONO (-3365 2085);
DISPLAY INVISIBLE (-3365 2085);
FORCEPROP 1 LASTPIN (-3375 2075) BN 7
J 0
(-3387 2083);
DISPLAY 0.489362 (-3387 2083);
PAINT GREEN (-3387 2083);
FORCEPROP 2 LAST CDS_LIB mstr_standard
J 2
(-3325 2075);
DISPLAY 0.723404 (-3325 2075);
PAINT MONO (-3325 2075);
DISPLAY INVISIBLE (-3325 2075);
FORCEPROP 1 LAST BODY_TYPE PLUMBING
J 0
(-3325 2125);
DISPLAY 0.872340 (-3325 2125);
PAINT GREEN (-3325 2125);
DISPLAY INVISIBLE (-3325 2125);
FORCEPROP 1 LAST HDL_TAP TRUE
J 0
(-3000 1950);
DISPLAY 0.872340 (-3000 1950);
DISPLAY INVISIBLE (-3000 1950);
FORCEPROP 1 LAST PATH I234
J 0
(-3327 2075);
DISPLAY 0.872340 (-3327 2075);
PAINT GREEN (-3327 2075);
DISPLAY INVISIBLE (-3327 2075);
FORCEADD OFFPAGE..6
R 2
(-2725 2025);
FORCEPROP 2 LAST $XR0 100 
J 0
(-2511 2025);
DISPLAY 0.638298 (-2511 2025);
PAINT MONO (-2511 2025);
FORCEPROP 2 LAST PATH I235
J 0
(-2500 2075);
DISPLAY 1.021277 (-2500 2075);
DISPLAY INVISIBLE (-2500 2075);
FORCEPROP 1 LAST COMMENT_BODY TRUE
J 2
(-2825 1950);
DISPLAY 0.872340 (-2825 1950);
PAINT GREEN (-2825 1950);
DISPLAY INVISIBLE (-2825 1950);
FORCEPROP 1 LAST OFFPAGE TRUE
J 2
(-3050 1900);
DISPLAY 0.872340 (-3050 1900);
PAINT GREEN (-3050 1900);
DISPLAY INVISIBLE (-3050 1900);
FORCEPROP 2 LAST CDS_LIB mstr_standard
J 2
(-2725 2025);
DISPLAY 0.723404 (-2725 2025);
PAINT MONO (-2725 2025);
DISPLAY INVISIBLE (-2725 2025);
FORCEADD TAP..1
(-3325 1925);
FORCEPROP 3 LASTPIN (-3375 1925) SIG_NAME M_D_CPU1_SB_CB<1>
J 0
(-3365 1935);
DISPLAY 0.659574 (-3365 1935);
PAINT MONO (-3365 1935);
DISPLAY INVISIBLE (-3365 1935);
FORCEPROP 1 LASTPIN (-3375 1925) BN 1
J 0
(-3387 1933);
DISPLAY 0.489362 (-3387 1933);
PAINT GREEN (-3387 1933);
FORCEPROP 2 LAST CDS_LIB mstr_standard
J 2
(-3325 1925);
DISPLAY 0.723404 (-3325 1925);
PAINT MONO (-3325 1925);
DISPLAY INVISIBLE (-3325 1925);
FORCEPROP 1 LAST BODY_TYPE PLUMBING
J 0
(-3325 1975);
DISPLAY 0.872340 (-3325 1975);
PAINT GREEN (-3325 1975);
DISPLAY INVISIBLE (-3325 1975);
FORCEPROP 1 LAST HDL_TAP TRUE
J 0
(-3000 1800);
DISPLAY 0.872340 (-3000 1800);
DISPLAY INVISIBLE (-3000 1800);
FORCEPROP 1 LAST PATH I236
J 0
(-3327 1925);
DISPLAY 0.872340 (-3327 1925);
PAINT GREEN (-3327 1925);
DISPLAY INVISIBLE (-3327 1925);
FORCEADD TAP..1
(-3325 1975);
FORCEPROP 3 LASTPIN (-3375 1975) SIG_NAME M_D_CPU1_SB_CB<0>
J 0
(-3365 1985);
DISPLAY 0.659574 (-3365 1985);
PAINT MONO (-3365 1985);
DISPLAY INVISIBLE (-3365 1985);
FORCEPROP 1 LASTPIN (-3375 1975) BN 0
J 0
(-3387 1983);
DISPLAY 0.489362 (-3387 1983);
PAINT GREEN (-3387 1983);
FORCEPROP 2 LAST CDS_LIB mstr_standard
J 2
(-3325 1975);
DISPLAY 0.723404 (-3325 1975);
PAINT MONO (-3325 1975);
DISPLAY INVISIBLE (-3325 1975);
FORCEPROP 1 LAST BODY_TYPE PLUMBING
J 0
(-3325 2025);
DISPLAY 0.872340 (-3325 2025);
PAINT GREEN (-3325 2025);
DISPLAY INVISIBLE (-3325 2025);
FORCEPROP 1 LAST HDL_TAP TRUE
J 0
(-3000 1850);
DISPLAY 0.872340 (-3000 1850);
DISPLAY INVISIBLE (-3000 1850);
FORCEPROP 1 LAST PATH I237
J 0
(-3327 1975);
DISPLAY 0.872340 (-3327 1975);
PAINT GREEN (-3327 1975);
DISPLAY INVISIBLE (-3327 1975);
FORCEADD TAP..1
(-3325 1825);
FORCEPROP 3 LASTPIN (-3375 1825) SIG_NAME M_D_CPU1_SB_CB<3>
J 0
(-3365 1835);
DISPLAY 0.659574 (-3365 1835);
PAINT MONO (-3365 1835);
DISPLAY INVISIBLE (-3365 1835);
FORCEPROP 1 LASTPIN (-3375 1825) BN 3
J 0
(-3387 1833);
DISPLAY 0.489362 (-3387 1833);
PAINT GREEN (-3387 1833);
FORCEPROP 2 LAST CDS_LIB mstr_standard
J 2
(-3325 1825);
DISPLAY 0.723404 (-3325 1825);
PAINT MONO (-3325 1825);
DISPLAY INVISIBLE (-3325 1825);
FORCEPROP 1 LAST BODY_TYPE PLUMBING
J 0
(-3325 1875);
DISPLAY 0.872340 (-3325 1875);
PAINT GREEN (-3325 1875);
DISPLAY INVISIBLE (-3325 1875);
FORCEPROP 1 LAST HDL_TAP TRUE
J 0
(-3000 1700);
DISPLAY 0.872340 (-3000 1700);
DISPLAY INVISIBLE (-3000 1700);
FORCEPROP 1 LAST PATH I238
J 0
(-3327 1825);
DISPLAY 0.872340 (-3327 1825);
PAINT GREEN (-3327 1825);
DISPLAY INVISIBLE (-3327 1825);
FORCEADD TAP..1
(-3325 1875);
FORCEPROP 3 LASTPIN (-3375 1875) SIG_NAME M_D_CPU1_SB_CB<2>
J 0
(-3365 1885);
DISPLAY 0.659574 (-3365 1885);
PAINT MONO (-3365 1885);
DISPLAY INVISIBLE (-3365 1885);
FORCEPROP 1 LASTPIN (-3375 1875) BN 2
J 0
(-3387 1883);
DISPLAY 0.489362 (-3387 1883);
PAINT GREEN (-3387 1883);
FORCEPROP 2 LAST CDS_LIB mstr_standard
J 2
(-3325 1875);
DISPLAY 0.723404 (-3325 1875);
PAINT MONO (-3325 1875);
DISPLAY INVISIBLE (-3325 1875);
FORCEPROP 1 LAST BODY_TYPE PLUMBING
J 0
(-3325 1925);
DISPLAY 0.872340 (-3325 1925);
PAINT GREEN (-3325 1925);
DISPLAY INVISIBLE (-3325 1925);
FORCEPROP 1 LAST HDL_TAP TRUE
J 0
(-3000 1750);
DISPLAY 0.872340 (-3000 1750);
DISPLAY INVISIBLE (-3000 1750);
FORCEPROP 1 LAST PATH I239
J 0
(-3327 1875);
DISPLAY 0.872340 (-3327 1875);
PAINT GREEN (-3327 1875);
DISPLAY INVISIBLE (-3327 1875);
FORCEADD TAP..1
(-3325 1625);
FORCEPROP 3 LASTPIN (-3375 1625) SIG_NAME M_D_CPU1_SB_CB<7>
J 0
(-3365 1635);
DISPLAY 0.659574 (-3365 1635);
PAINT MONO (-3365 1635);
DISPLAY INVISIBLE (-3365 1635);
FORCEPROP 1 LASTPIN (-3375 1625) BN 7
J 0
(-3387 1633);
DISPLAY 0.489362 (-3387 1633);
PAINT GREEN (-3387 1633);
FORCEPROP 2 LAST CDS_LIB mstr_standard
J 2
(-3325 1625);
DISPLAY 0.723404 (-3325 1625);
PAINT MONO (-3325 1625);
DISPLAY INVISIBLE (-3325 1625);
FORCEPROP 1 LAST BODY_TYPE PLUMBING
J 0
(-3325 1675);
DISPLAY 0.872340 (-3325 1675);
PAINT GREEN (-3325 1675);
DISPLAY INVISIBLE (-3325 1675);
FORCEPROP 1 LAST HDL_TAP TRUE
J 0
(-3000 1500);
DISPLAY 0.872340 (-3000 1500);
DISPLAY INVISIBLE (-3000 1500);
FORCEPROP 1 LAST PATH I240
J 0
(-3327 1625);
DISPLAY 0.872340 (-3327 1625);
PAINT GREEN (-3327 1625);
DISPLAY INVISIBLE (-3327 1625);
FORCEADD TAP..1
(-3325 1675);
FORCEPROP 3 LASTPIN (-3375 1675) SIG_NAME M_D_CPU1_SB_CB<6>
J 0
(-3365 1685);
DISPLAY 0.659574 (-3365 1685);
PAINT MONO (-3365 1685);
DISPLAY INVISIBLE (-3365 1685);
FORCEPROP 1 LASTPIN (-3375 1675) BN 6
J 0
(-3387 1683);
DISPLAY 0.489362 (-3387 1683);
PAINT GREEN (-3387 1683);
FORCEPROP 2 LAST CDS_LIB mstr_standard
J 2
(-3325 1675);
DISPLAY 0.723404 (-3325 1675);
PAINT MONO (-3325 1675);
DISPLAY INVISIBLE (-3325 1675);
FORCEPROP 1 LAST BODY_TYPE PLUMBING
J 0
(-3325 1725);
DISPLAY 0.872340 (-3325 1725);
PAINT GREEN (-3325 1725);
DISPLAY INVISIBLE (-3325 1725);
FORCEPROP 1 LAST HDL_TAP TRUE
J 0
(-3000 1550);
DISPLAY 0.872340 (-3000 1550);
DISPLAY INVISIBLE (-3000 1550);
FORCEPROP 1 LAST PATH I241
J 0
(-3327 1675);
DISPLAY 0.872340 (-3327 1675);
PAINT GREEN (-3327 1675);
DISPLAY INVISIBLE (-3327 1675);
FORCEADD TAP..1
(-3325 1775);
FORCEPROP 3 LASTPIN (-3375 1775) SIG_NAME M_D_CPU1_SB_CB<4>
J 0
(-3365 1785);
DISPLAY 0.659574 (-3365 1785);
PAINT MONO (-3365 1785);
DISPLAY INVISIBLE (-3365 1785);
FORCEPROP 1 LASTPIN (-3375 1775) BN 4
J 0
(-3387 1783);
DISPLAY 0.489362 (-3387 1783);
PAINT GREEN (-3387 1783);
FORCEPROP 2 LAST CDS_LIB mstr_standard
J 2
(-3325 1775);
DISPLAY 0.723404 (-3325 1775);
PAINT MONO (-3325 1775);
DISPLAY INVISIBLE (-3325 1775);
FORCEPROP 1 LAST BODY_TYPE PLUMBING
J 0
(-3325 1825);
DISPLAY 0.872340 (-3325 1825);
PAINT GREEN (-3325 1825);
DISPLAY INVISIBLE (-3325 1825);
FORCEPROP 1 LAST HDL_TAP TRUE
J 0
(-3000 1650);
DISPLAY 0.872340 (-3000 1650);
DISPLAY INVISIBLE (-3000 1650);
FORCEPROP 1 LAST PATH I242
J 0
(-3327 1775);
DISPLAY 0.872340 (-3327 1775);
PAINT GREEN (-3327 1775);
DISPLAY INVISIBLE (-3327 1775);
FORCEADD TAP..1
(-3325 1725);
FORCEPROP 3 LASTPIN (-3375 1725) SIG_NAME M_D_CPU1_SB_CB<5>
J 0
(-3365 1735);
DISPLAY 0.659574 (-3365 1735);
PAINT MONO (-3365 1735);
DISPLAY INVISIBLE (-3365 1735);
FORCEPROP 1 LASTPIN (-3375 1725) BN 5
J 0
(-3387 1733);
DISPLAY 0.489362 (-3387 1733);
PAINT GREEN (-3387 1733);
FORCEPROP 2 LAST CDS_LIB mstr_standard
J 2
(-3325 1725);
DISPLAY 0.723404 (-3325 1725);
PAINT MONO (-3325 1725);
DISPLAY INVISIBLE (-3325 1725);
FORCEPROP 1 LAST BODY_TYPE PLUMBING
J 0
(-3325 1775);
DISPLAY 0.872340 (-3325 1775);
PAINT GREEN (-3325 1775);
DISPLAY INVISIBLE (-3325 1775);
FORCEPROP 1 LAST HDL_TAP TRUE
J 0
(-3000 1600);
DISPLAY 0.872340 (-3000 1600);
DISPLAY INVISIBLE (-3000 1600);
FORCEPROP 1 LAST PATH I243
J 0
(-3327 1725);
DISPLAY 0.872340 (-3327 1725);
PAINT GREEN (-3327 1725);
DISPLAY INVISIBLE (-3327 1725);
FORCEADD TAP..1
R 2
(-5750 6025);
FORCEPROP 3 LASTPIN (-5700 6025) SIG_NAME M_D_CPU1_SA_DQS_DP<0>
J 0
(-5690 6035);
DISPLAY 0.659574 (-5690 6035);
PAINT MONO (-5690 6035);
DISPLAY INVISIBLE (-5690 6035);
FORCEPROP 1 LASTPIN (-5700 6025) BN 0
J 2
(-5688 6033);
DISPLAY 0.489362 (-5688 6033);
PAINT GREEN (-5688 6033);
FORCEPROP 2 LAST CDS_LIB mstr_standard
J 2
(-5750 6025);
DISPLAY 0.723404 (-5750 6025);
PAINT MONO (-5750 6025);
DISPLAY INVISIBLE (-5750 6025);
FORCEPROP 1 LAST BODY_TYPE PLUMBING
J 2
(-5750 6075);
DISPLAY 0.872340 (-5750 6075);
PAINT GREEN (-5750 6075);
DISPLAY INVISIBLE (-5750 6075);
FORCEPROP 1 LAST HDL_TAP TRUE
J 2
(-6075 5900);
DISPLAY 0.872340 (-6075 5900);
DISPLAY INVISIBLE (-6075 5900);
FORCEPROP 1 LAST PATH I244
J 2
(-5748 6025);
DISPLAY 0.872340 (-5748 6025);
PAINT GREEN (-5748 6025);
DISPLAY INVISIBLE (-5748 6025);
FORCEADD TAP..1
R 2
(-5750 5925);
FORCEPROP 3 LASTPIN (-5700 5925) SIG_NAME M_D_CPU1_SA_DQS_DP<1>
J 0
(-5690 5935);
DISPLAY 0.659574 (-5690 5935);
PAINT MONO (-5690 5935);
DISPLAY INVISIBLE (-5690 5935);
FORCEPROP 1 LASTPIN (-5700 5925) BN 1
J 2
(-5688 5933);
DISPLAY 0.489362 (-5688 5933);
PAINT GREEN (-5688 5933);
FORCEPROP 2 LAST CDS_LIB mstr_standard
J 2
(-5750 5925);
DISPLAY 0.723404 (-5750 5925);
PAINT MONO (-5750 5925);
DISPLAY INVISIBLE (-5750 5925);
FORCEPROP 1 LAST BODY_TYPE PLUMBING
J 2
(-5750 5975);
DISPLAY 0.872340 (-5750 5975);
PAINT GREEN (-5750 5975);
DISPLAY INVISIBLE (-5750 5975);
FORCEPROP 1 LAST HDL_TAP TRUE
J 2
(-6075 5800);
DISPLAY 0.872340 (-6075 5800);
DISPLAY INVISIBLE (-6075 5800);
FORCEPROP 1 LAST PATH I245
J 2
(-5748 5925);
DISPLAY 0.872340 (-5748 5925);
PAINT GREEN (-5748 5925);
DISPLAY INVISIBLE (-5748 5925);
FORCEADD TAP..1
R 2
(-5750 5825);
FORCEPROP 3 LASTPIN (-5700 5825) SIG_NAME M_D_CPU1_SA_DQS_DP<2>
J 0
(-5690 5835);
DISPLAY 0.659574 (-5690 5835);
PAINT MONO (-5690 5835);
DISPLAY INVISIBLE (-5690 5835);
FORCEPROP 1 LASTPIN (-5700 5825) BN 2
J 2
(-5688 5833);
DISPLAY 0.489362 (-5688 5833);
PAINT GREEN (-5688 5833);
FORCEPROP 2 LAST CDS_LIB mstr_standard
J 2
(-5750 5825);
DISPLAY 0.723404 (-5750 5825);
PAINT MONO (-5750 5825);
DISPLAY INVISIBLE (-5750 5825);
FORCEPROP 1 LAST BODY_TYPE PLUMBING
J 2
(-5750 5875);
DISPLAY 0.872340 (-5750 5875);
PAINT GREEN (-5750 5875);
DISPLAY INVISIBLE (-5750 5875);
FORCEPROP 1 LAST HDL_TAP TRUE
J 2
(-6075 5700);
DISPLAY 0.872340 (-6075 5700);
DISPLAY INVISIBLE (-6075 5700);
FORCEPROP 1 LAST PATH I246
J 2
(-5748 5825);
DISPLAY 0.872340 (-5748 5825);
PAINT GREEN (-5748 5825);
DISPLAY INVISIBLE (-5748 5825);
FORCEADD TAP..1
R 2
(-5750 5725);
FORCEPROP 3 LASTPIN (-5700 5725) SIG_NAME M_D_CPU1_SA_DQS_DP<3>
J 0
(-5690 5735);
DISPLAY 0.659574 (-5690 5735);
PAINT MONO (-5690 5735);
DISPLAY INVISIBLE (-5690 5735);
FORCEPROP 1 LASTPIN (-5700 5725) BN 3
J 2
(-5688 5733);
DISPLAY 0.489362 (-5688 5733);
PAINT GREEN (-5688 5733);
FORCEPROP 2 LAST CDS_LIB mstr_standard
J 2
(-5750 5725);
DISPLAY 0.723404 (-5750 5725);
PAINT MONO (-5750 5725);
DISPLAY INVISIBLE (-5750 5725);
FORCEPROP 1 LAST BODY_TYPE PLUMBING
J 2
(-5750 5775);
DISPLAY 0.872340 (-5750 5775);
PAINT GREEN (-5750 5775);
DISPLAY INVISIBLE (-5750 5775);
FORCEPROP 1 LAST HDL_TAP TRUE
J 2
(-6075 5600);
DISPLAY 0.872340 (-6075 5600);
DISPLAY INVISIBLE (-6075 5600);
FORCEPROP 1 LAST PATH I247
J 2
(-5748 5725);
DISPLAY 0.872340 (-5748 5725);
PAINT GREEN (-5748 5725);
DISPLAY INVISIBLE (-5748 5725);
FORCEADD TAP..1
R 2
(-5950 5975);
FORCEPROP 3 LASTPIN (-5900 5975) SIG_NAME M_D_CPU1_SA_DQS_DN<0>
J 0
(-5890 5985);
DISPLAY 0.659574 (-5890 5985);
PAINT MONO (-5890 5985);
DISPLAY INVISIBLE (-5890 5985);
FORCEPROP 1 LASTPIN (-5900 5975) BN 0
J 2
(-5888 5983);
DISPLAY 0.489362 (-5888 5983);
PAINT GREEN (-5888 5983);
FORCEPROP 2 LAST CDS_LIB mstr_standard
J 2
(-5950 5975);
DISPLAY 0.723404 (-5950 5975);
PAINT MONO (-5950 5975);
DISPLAY INVISIBLE (-5950 5975);
FORCEPROP 1 LAST BODY_TYPE PLUMBING
J 2
(-5950 6025);
DISPLAY 0.872340 (-5950 6025);
PAINT GREEN (-5950 6025);
DISPLAY INVISIBLE (-5950 6025);
FORCEPROP 1 LAST HDL_TAP TRUE
J 2
(-6275 5850);
DISPLAY 0.872340 (-6275 5850);
DISPLAY INVISIBLE (-6275 5850);
FORCEPROP 1 LAST PATH I248
J 2
(-5948 5975);
DISPLAY 0.872340 (-5948 5975);
PAINT GREEN (-5948 5975);
DISPLAY INVISIBLE (-5948 5975);
FORCEADD TAP..1
R 2
(-5950 5875);
FORCEPROP 3 LASTPIN (-5900 5875) SIG_NAME M_D_CPU1_SA_DQS_DN<1>
J 0
(-5890 5885);
DISPLAY 0.659574 (-5890 5885);
PAINT MONO (-5890 5885);
DISPLAY INVISIBLE (-5890 5885);
FORCEPROP 1 LASTPIN (-5900 5875) BN 1
J 2
(-5888 5883);
DISPLAY 0.489362 (-5888 5883);
PAINT GREEN (-5888 5883);
FORCEPROP 2 LAST CDS_LIB mstr_standard
J 2
(-5950 5875);
DISPLAY 0.723404 (-5950 5875);
PAINT MONO (-5950 5875);
DISPLAY INVISIBLE (-5950 5875);
FORCEPROP 1 LAST BODY_TYPE PLUMBING
J 2
(-5950 5925);
DISPLAY 0.872340 (-5950 5925);
PAINT GREEN (-5950 5925);
DISPLAY INVISIBLE (-5950 5925);
FORCEPROP 1 LAST HDL_TAP TRUE
J 2
(-6275 5750);
DISPLAY 0.872340 (-6275 5750);
DISPLAY INVISIBLE (-6275 5750);
FORCEPROP 1 LAST PATH I249
J 2
(-5948 5875);
DISPLAY 0.872340 (-5948 5875);
PAINT GREEN (-5948 5875);
DISPLAY INVISIBLE (-5948 5875);
FORCEADD TAP..1
R 2
(-5950 5775);
FORCEPROP 3 LASTPIN (-5900 5775) SIG_NAME M_D_CPU1_SA_DQS_DN<2>
J 0
(-5890 5785);
DISPLAY 0.659574 (-5890 5785);
PAINT MONO (-5890 5785);
DISPLAY INVISIBLE (-5890 5785);
FORCEPROP 1 LASTPIN (-5900 5775) BN 2
J 2
(-5888 5783);
DISPLAY 0.489362 (-5888 5783);
PAINT GREEN (-5888 5783);
FORCEPROP 2 LAST CDS_LIB mstr_standard
J 2
(-5950 5775);
DISPLAY 0.723404 (-5950 5775);
PAINT MONO (-5950 5775);
DISPLAY INVISIBLE (-5950 5775);
FORCEPROP 1 LAST BODY_TYPE PLUMBING
J 2
(-5950 5825);
DISPLAY 0.872340 (-5950 5825);
PAINT GREEN (-5950 5825);
DISPLAY INVISIBLE (-5950 5825);
FORCEPROP 1 LAST HDL_TAP TRUE
J 2
(-6275 5650);
DISPLAY 0.872340 (-6275 5650);
DISPLAY INVISIBLE (-6275 5650);
FORCEPROP 1 LAST PATH I250
J 2
(-5948 5775);
DISPLAY 0.872340 (-5948 5775);
PAINT GREEN (-5948 5775);
DISPLAY INVISIBLE (-5948 5775);
FORCEADD TAP..1
R 2
(-5950 5675);
FORCEPROP 3 LASTPIN (-5900 5675) SIG_NAME M_D_CPU1_SA_DQS_DN<3>
J 0
(-5890 5685);
DISPLAY 0.659574 (-5890 5685);
PAINT MONO (-5890 5685);
DISPLAY INVISIBLE (-5890 5685);
FORCEPROP 1 LASTPIN (-5900 5675) BN 3
J 2
(-5888 5683);
DISPLAY 0.489362 (-5888 5683);
PAINT GREEN (-5888 5683);
FORCEPROP 2 LAST CDS_LIB mstr_standard
J 2
(-5950 5675);
DISPLAY 0.723404 (-5950 5675);
PAINT MONO (-5950 5675);
DISPLAY INVISIBLE (-5950 5675);
FORCEPROP 1 LAST BODY_TYPE PLUMBING
J 2
(-5950 5725);
DISPLAY 0.872340 (-5950 5725);
PAINT GREEN (-5950 5725);
DISPLAY INVISIBLE (-5950 5725);
FORCEPROP 1 LAST HDL_TAP TRUE
J 2
(-6275 5550);
DISPLAY 0.872340 (-6275 5550);
DISPLAY INVISIBLE (-6275 5550);
FORCEPROP 1 LAST PATH I251
J 2
(-5948 5675);
DISPLAY 0.872340 (-5948 5675);
PAINT GREEN (-5948 5675);
DISPLAY INVISIBLE (-5948 5675);
FORCEADD TAP..1
R 2
(-5750 5625);
FORCEPROP 3 LASTPIN (-5700 5625) SIG_NAME M_D_CPU1_SA_DQS_DP<4>
J 0
(-5690 5635);
DISPLAY 0.659574 (-5690 5635);
PAINT MONO (-5690 5635);
DISPLAY INVISIBLE (-5690 5635);
FORCEPROP 1 LASTPIN (-5700 5625) BN 4
J 2
(-5688 5633);
DISPLAY 0.489362 (-5688 5633);
PAINT GREEN (-5688 5633);
FORCEPROP 2 LAST CDS_LIB mstr_standard
J 2
(-5750 5625);
DISPLAY 0.723404 (-5750 5625);
PAINT MONO (-5750 5625);
DISPLAY INVISIBLE (-5750 5625);
FORCEPROP 1 LAST BODY_TYPE PLUMBING
J 2
(-5750 5675);
DISPLAY 0.872340 (-5750 5675);
PAINT GREEN (-5750 5675);
DISPLAY INVISIBLE (-5750 5675);
FORCEPROP 1 LAST HDL_TAP TRUE
J 2
(-6075 5500);
DISPLAY 0.872340 (-6075 5500);
DISPLAY INVISIBLE (-6075 5500);
FORCEPROP 1 LAST PATH I252
J 2
(-5748 5625);
DISPLAY 0.872340 (-5748 5625);
PAINT GREEN (-5748 5625);
DISPLAY INVISIBLE (-5748 5625);
FORCEADD TAP..1
R 2
(-5750 5525);
FORCEPROP 3 LASTPIN (-5700 5525) SIG_NAME M_D_CPU1_SA_DQS_DP<5>
J 0
(-5690 5535);
DISPLAY 0.659574 (-5690 5535);
PAINT MONO (-5690 5535);
DISPLAY INVISIBLE (-5690 5535);
FORCEPROP 1 LASTPIN (-5700 5525) BN 5
J 2
(-5688 5533);
DISPLAY 0.489362 (-5688 5533);
PAINT GREEN (-5688 5533);
FORCEPROP 2 LAST CDS_LIB mstr_standard
J 2
(-5750 5525);
DISPLAY 0.723404 (-5750 5525);
PAINT MONO (-5750 5525);
DISPLAY INVISIBLE (-5750 5525);
FORCEPROP 1 LAST BODY_TYPE PLUMBING
J 2
(-5750 5575);
DISPLAY 0.872340 (-5750 5575);
PAINT GREEN (-5750 5575);
DISPLAY INVISIBLE (-5750 5575);
FORCEPROP 1 LAST HDL_TAP TRUE
J 2
(-6075 5400);
DISPLAY 0.872340 (-6075 5400);
DISPLAY INVISIBLE (-6075 5400);
FORCEPROP 1 LAST PATH I253
J 2
(-5748 5525);
DISPLAY 0.872340 (-5748 5525);
PAINT GREEN (-5748 5525);
DISPLAY INVISIBLE (-5748 5525);
FORCEADD TAP..1
R 2
(-5750 5425);
FORCEPROP 3 LASTPIN (-5700 5425) SIG_NAME M_D_CPU1_SA_DQS_DP<6>
J 0
(-5690 5435);
DISPLAY 0.659574 (-5690 5435);
PAINT MONO (-5690 5435);
DISPLAY INVISIBLE (-5690 5435);
FORCEPROP 1 LASTPIN (-5700 5425) BN 6
J 2
(-5688 5433);
DISPLAY 0.489362 (-5688 5433);
PAINT GREEN (-5688 5433);
FORCEPROP 2 LAST CDS_LIB mstr_standard
J 2
(-5750 5425);
DISPLAY 0.723404 (-5750 5425);
PAINT MONO (-5750 5425);
DISPLAY INVISIBLE (-5750 5425);
FORCEPROP 1 LAST BODY_TYPE PLUMBING
J 2
(-5750 5475);
DISPLAY 0.872340 (-5750 5475);
PAINT GREEN (-5750 5475);
DISPLAY INVISIBLE (-5750 5475);
FORCEPROP 1 LAST HDL_TAP TRUE
J 2
(-6075 5300);
DISPLAY 0.872340 (-6075 5300);
DISPLAY INVISIBLE (-6075 5300);
FORCEPROP 1 LAST PATH I254
J 2
(-5748 5425);
DISPLAY 0.872340 (-5748 5425);
PAINT GREEN (-5748 5425);
DISPLAY INVISIBLE (-5748 5425);
FORCEADD TAP..1
R 2
(-5750 5325);
FORCEPROP 3 LASTPIN (-5700 5325) SIG_NAME M_D_CPU1_SA_DQS_DP<7>
J 0
(-5690 5335);
DISPLAY 0.659574 (-5690 5335);
PAINT MONO (-5690 5335);
DISPLAY INVISIBLE (-5690 5335);
FORCEPROP 1 LASTPIN (-5700 5325) BN 7
J 2
(-5688 5333);
DISPLAY 0.489362 (-5688 5333);
PAINT GREEN (-5688 5333);
FORCEPROP 2 LAST CDS_LIB mstr_standard
J 2
(-5750 5325);
DISPLAY 0.723404 (-5750 5325);
PAINT MONO (-5750 5325);
DISPLAY INVISIBLE (-5750 5325);
FORCEPROP 1 LAST BODY_TYPE PLUMBING
J 2
(-5750 5375);
DISPLAY 0.872340 (-5750 5375);
PAINT GREEN (-5750 5375);
DISPLAY INVISIBLE (-5750 5375);
FORCEPROP 1 LAST HDL_TAP TRUE
J 2
(-6075 5200);
DISPLAY 0.872340 (-6075 5200);
DISPLAY INVISIBLE (-6075 5200);
FORCEPROP 1 LAST PATH I255
J 2
(-5748 5325);
DISPLAY 0.872340 (-5748 5325);
PAINT GREEN (-5748 5325);
DISPLAY INVISIBLE (-5748 5325);
FORCEADD TAP..1
R 2
(-5750 5225);
FORCEPROP 3 LASTPIN (-5700 5225) SIG_NAME M_D_CPU1_SA_DQS_DP<8>
J 0
(-5690 5235);
DISPLAY 0.659574 (-5690 5235);
PAINT MONO (-5690 5235);
DISPLAY INVISIBLE (-5690 5235);
FORCEPROP 1 LASTPIN (-5700 5225) BN 8
J 2
(-5688 5233);
DISPLAY 0.489362 (-5688 5233);
PAINT GREEN (-5688 5233);
FORCEPROP 2 LAST CDS_LIB mstr_standard
J 2
(-5750 5225);
DISPLAY 0.723404 (-5750 5225);
PAINT MONO (-5750 5225);
DISPLAY INVISIBLE (-5750 5225);
FORCEPROP 1 LAST BODY_TYPE PLUMBING
J 2
(-5750 5275);
DISPLAY 0.872340 (-5750 5275);
PAINT GREEN (-5750 5275);
DISPLAY INVISIBLE (-5750 5275);
FORCEPROP 1 LAST HDL_TAP TRUE
J 2
(-6075 5100);
DISPLAY 0.872340 (-6075 5100);
DISPLAY INVISIBLE (-6075 5100);
FORCEPROP 1 LAST PATH I256
J 2
(-5748 5225);
DISPLAY 0.872340 (-5748 5225);
PAINT GREEN (-5748 5225);
DISPLAY INVISIBLE (-5748 5225);
FORCEADD TAP..1
R 2
(-5750 5125);
FORCEPROP 3 LASTPIN (-5700 5125) SIG_NAME M_D_CPU1_SA_DQS_DP<9>
J 0
(-5690 5135);
DISPLAY 0.659574 (-5690 5135);
PAINT MONO (-5690 5135);
DISPLAY INVISIBLE (-5690 5135);
FORCEPROP 1 LASTPIN (-5700 5125) BN 9
J 2
(-5688 5133);
DISPLAY 0.489362 (-5688 5133);
PAINT GREEN (-5688 5133);
FORCEPROP 2 LAST CDS_LIB mstr_standard
J 2
(-5750 5125);
DISPLAY 0.723404 (-5750 5125);
PAINT MONO (-5750 5125);
DISPLAY INVISIBLE (-5750 5125);
FORCEPROP 1 LAST BODY_TYPE PLUMBING
J 2
(-5750 5175);
DISPLAY 0.872340 (-5750 5175);
PAINT GREEN (-5750 5175);
DISPLAY INVISIBLE (-5750 5175);
FORCEPROP 1 LAST HDL_TAP TRUE
J 2
(-6075 5000);
DISPLAY 0.872340 (-6075 5000);
DISPLAY INVISIBLE (-6075 5000);
FORCEPROP 1 LAST PATH I257
J 2
(-5748 5125);
DISPLAY 0.872340 (-5748 5125);
PAINT GREEN (-5748 5125);
DISPLAY INVISIBLE (-5748 5125);
FORCEADD TAP..1
R 2
(-5950 5575);
FORCEPROP 3 LASTPIN (-5900 5575) SIG_NAME M_D_CPU1_SA_DQS_DN<4>
J 0
(-5890 5585);
DISPLAY 0.659574 (-5890 5585);
PAINT MONO (-5890 5585);
DISPLAY INVISIBLE (-5890 5585);
FORCEPROP 1 LASTPIN (-5900 5575) BN 4
J 2
(-5888 5583);
DISPLAY 0.489362 (-5888 5583);
PAINT GREEN (-5888 5583);
FORCEPROP 2 LAST CDS_LIB mstr_standard
J 2
(-5950 5575);
DISPLAY 0.723404 (-5950 5575);
PAINT MONO (-5950 5575);
DISPLAY INVISIBLE (-5950 5575);
FORCEPROP 1 LAST BODY_TYPE PLUMBING
J 2
(-5950 5625);
DISPLAY 0.872340 (-5950 5625);
PAINT GREEN (-5950 5625);
DISPLAY INVISIBLE (-5950 5625);
FORCEPROP 1 LAST HDL_TAP TRUE
J 2
(-6275 5450);
DISPLAY 0.872340 (-6275 5450);
DISPLAY INVISIBLE (-6275 5450);
FORCEPROP 1 LAST PATH I258
J 2
(-5948 5575);
DISPLAY 0.872340 (-5948 5575);
PAINT GREEN (-5948 5575);
DISPLAY INVISIBLE (-5948 5575);
FORCEADD TAP..1
R 2
(-5950 5475);
FORCEPROP 3 LASTPIN (-5900 5475) SIG_NAME M_D_CPU1_SA_DQS_DN<5>
J 0
(-5890 5485);
DISPLAY 0.659574 (-5890 5485);
PAINT MONO (-5890 5485);
DISPLAY INVISIBLE (-5890 5485);
FORCEPROP 1 LASTPIN (-5900 5475) BN 5
J 2
(-5888 5483);
DISPLAY 0.489362 (-5888 5483);
PAINT GREEN (-5888 5483);
FORCEPROP 2 LAST CDS_LIB mstr_standard
J 2
(-5950 5475);
DISPLAY 0.723404 (-5950 5475);
PAINT MONO (-5950 5475);
DISPLAY INVISIBLE (-5950 5475);
FORCEPROP 1 LAST BODY_TYPE PLUMBING
J 2
(-5950 5525);
DISPLAY 0.872340 (-5950 5525);
PAINT GREEN (-5950 5525);
DISPLAY INVISIBLE (-5950 5525);
FORCEPROP 1 LAST HDL_TAP TRUE
J 2
(-6275 5350);
DISPLAY 0.872340 (-6275 5350);
DISPLAY INVISIBLE (-6275 5350);
FORCEPROP 1 LAST PATH I259
J 2
(-5948 5475);
DISPLAY 0.872340 (-5948 5475);
PAINT GREEN (-5948 5475);
DISPLAY INVISIBLE (-5948 5475);
FORCEADD TAP..1
R 2
(-5950 5375);
FORCEPROP 3 LASTPIN (-5900 5375) SIG_NAME M_D_CPU1_SA_DQS_DN<6>
J 0
(-5890 5385);
DISPLAY 0.659574 (-5890 5385);
PAINT MONO (-5890 5385);
DISPLAY INVISIBLE (-5890 5385);
FORCEPROP 1 LASTPIN (-5900 5375) BN 6
J 2
(-5888 5383);
DISPLAY 0.489362 (-5888 5383);
PAINT GREEN (-5888 5383);
FORCEPROP 2 LAST CDS_LIB mstr_standard
J 2
(-5950 5375);
DISPLAY 0.723404 (-5950 5375);
PAINT MONO (-5950 5375);
DISPLAY INVISIBLE (-5950 5375);
FORCEPROP 1 LAST BODY_TYPE PLUMBING
J 2
(-5950 5425);
DISPLAY 0.872340 (-5950 5425);
PAINT GREEN (-5950 5425);
DISPLAY INVISIBLE (-5950 5425);
FORCEPROP 1 LAST HDL_TAP TRUE
J 2
(-6275 5250);
DISPLAY 0.872340 (-6275 5250);
DISPLAY INVISIBLE (-6275 5250);
FORCEPROP 1 LAST PATH I260
J 2
(-5948 5375);
DISPLAY 0.872340 (-5948 5375);
PAINT GREEN (-5948 5375);
DISPLAY INVISIBLE (-5948 5375);
FORCEADD TAP..1
R 2
(-5950 5275);
FORCEPROP 3 LASTPIN (-5900 5275) SIG_NAME M_D_CPU1_SA_DQS_DN<7>
J 0
(-5890 5285);
DISPLAY 0.659574 (-5890 5285);
PAINT MONO (-5890 5285);
DISPLAY INVISIBLE (-5890 5285);
FORCEPROP 1 LASTPIN (-5900 5275) BN 7
J 2
(-5888 5283);
DISPLAY 0.489362 (-5888 5283);
PAINT GREEN (-5888 5283);
FORCEPROP 2 LAST CDS_LIB mstr_standard
J 2
(-5950 5275);
DISPLAY 0.723404 (-5950 5275);
PAINT MONO (-5950 5275);
DISPLAY INVISIBLE (-5950 5275);
FORCEPROP 1 LAST BODY_TYPE PLUMBING
J 2
(-5950 5325);
DISPLAY 0.872340 (-5950 5325);
PAINT GREEN (-5950 5325);
DISPLAY INVISIBLE (-5950 5325);
FORCEPROP 1 LAST HDL_TAP TRUE
J 2
(-6275 5150);
DISPLAY 0.872340 (-6275 5150);
DISPLAY INVISIBLE (-6275 5150);
FORCEPROP 1 LAST PATH I261
J 2
(-5948 5275);
DISPLAY 0.872340 (-5948 5275);
PAINT GREEN (-5948 5275);
DISPLAY INVISIBLE (-5948 5275);
FORCEADD TAP..1
R 2
(-5950 5175);
FORCEPROP 3 LASTPIN (-5900 5175) SIG_NAME M_D_CPU1_SA_DQS_DN<8>
J 0
(-5890 5185);
DISPLAY 0.659574 (-5890 5185);
PAINT MONO (-5890 5185);
DISPLAY INVISIBLE (-5890 5185);
FORCEPROP 1 LASTPIN (-5900 5175) BN 8
J 2
(-5888 5183);
DISPLAY 0.489362 (-5888 5183);
PAINT GREEN (-5888 5183);
FORCEPROP 2 LAST CDS_LIB mstr_standard
J 2
(-5950 5175);
DISPLAY 0.723404 (-5950 5175);
PAINT MONO (-5950 5175);
DISPLAY INVISIBLE (-5950 5175);
FORCEPROP 1 LAST BODY_TYPE PLUMBING
J 2
(-5950 5225);
DISPLAY 0.872340 (-5950 5225);
PAINT GREEN (-5950 5225);
DISPLAY INVISIBLE (-5950 5225);
FORCEPROP 1 LAST HDL_TAP TRUE
J 2
(-6275 5050);
DISPLAY 0.872340 (-6275 5050);
DISPLAY INVISIBLE (-6275 5050);
FORCEPROP 1 LAST PATH I262
J 2
(-5948 5175);
DISPLAY 0.872340 (-5948 5175);
PAINT GREEN (-5948 5175);
DISPLAY INVISIBLE (-5948 5175);
FORCEADD TAP..1
R 2
(-5750 4975);
FORCEPROP 3 LASTPIN (-5700 4975) SIG_NAME M_D_CPU1_SB_DQS_DP<0>
J 0
(-5690 4985);
DISPLAY 0.659574 (-5690 4985);
PAINT MONO (-5690 4985);
DISPLAY INVISIBLE (-5690 4985);
FORCEPROP 1 LASTPIN (-5700 4975) BN 0
J 2
(-5688 4983);
DISPLAY 0.489362 (-5688 4983);
PAINT GREEN (-5688 4983);
FORCEPROP 2 LAST CDS_LIB mstr_standard
J 2
(-5750 4975);
DISPLAY 0.723404 (-5750 4975);
PAINT MONO (-5750 4975);
DISPLAY INVISIBLE (-5750 4975);
FORCEPROP 1 LAST BODY_TYPE PLUMBING
J 2
(-5750 5025);
DISPLAY 0.872340 (-5750 5025);
PAINT GREEN (-5750 5025);
DISPLAY INVISIBLE (-5750 5025);
FORCEPROP 1 LAST HDL_TAP TRUE
J 2
(-6075 4850);
DISPLAY 0.872340 (-6075 4850);
DISPLAY INVISIBLE (-6075 4850);
FORCEPROP 1 LAST PATH I263
J 2
(-5748 4975);
DISPLAY 0.872340 (-5748 4975);
PAINT GREEN (-5748 4975);
DISPLAY INVISIBLE (-5748 4975);
FORCEADD TAP..1
R 2
(-5750 4875);
FORCEPROP 3 LASTPIN (-5700 4875) SIG_NAME M_D_CPU1_SB_DQS_DP<1>
J 0
(-5690 4885);
DISPLAY 0.659574 (-5690 4885);
PAINT MONO (-5690 4885);
DISPLAY INVISIBLE (-5690 4885);
FORCEPROP 1 LASTPIN (-5700 4875) BN 1
J 2
(-5688 4883);
DISPLAY 0.489362 (-5688 4883);
PAINT GREEN (-5688 4883);
FORCEPROP 2 LAST CDS_LIB mstr_standard
J 2
(-5750 4875);
DISPLAY 0.723404 (-5750 4875);
PAINT MONO (-5750 4875);
DISPLAY INVISIBLE (-5750 4875);
FORCEPROP 1 LAST BODY_TYPE PLUMBING
J 2
(-5750 4925);
DISPLAY 0.872340 (-5750 4925);
PAINT GREEN (-5750 4925);
DISPLAY INVISIBLE (-5750 4925);
FORCEPROP 1 LAST HDL_TAP TRUE
J 2
(-6075 4750);
DISPLAY 0.872340 (-6075 4750);
DISPLAY INVISIBLE (-6075 4750);
FORCEPROP 1 LAST PATH I264
J 2
(-5748 4875);
DISPLAY 0.872340 (-5748 4875);
PAINT GREEN (-5748 4875);
DISPLAY INVISIBLE (-5748 4875);
FORCEADD TAP..1
R 2
(-5750 4775);
FORCEPROP 3 LASTPIN (-5700 4775) SIG_NAME M_D_CPU1_SB_DQS_DP<2>
J 0
(-5690 4785);
DISPLAY 0.659574 (-5690 4785);
PAINT MONO (-5690 4785);
DISPLAY INVISIBLE (-5690 4785);
FORCEPROP 1 LASTPIN (-5700 4775) BN 2
J 2
(-5688 4783);
DISPLAY 0.489362 (-5688 4783);
PAINT GREEN (-5688 4783);
FORCEPROP 2 LAST CDS_LIB mstr_standard
J 2
(-5750 4775);
DISPLAY 0.723404 (-5750 4775);
PAINT MONO (-5750 4775);
DISPLAY INVISIBLE (-5750 4775);
FORCEPROP 1 LAST BODY_TYPE PLUMBING
J 2
(-5750 4825);
DISPLAY 0.872340 (-5750 4825);
PAINT GREEN (-5750 4825);
DISPLAY INVISIBLE (-5750 4825);
FORCEPROP 1 LAST HDL_TAP TRUE
J 2
(-6075 4650);
DISPLAY 0.872340 (-6075 4650);
DISPLAY INVISIBLE (-6075 4650);
FORCEPROP 1 LAST PATH I265
J 2
(-5748 4775);
DISPLAY 0.872340 (-5748 4775);
PAINT GREEN (-5748 4775);
DISPLAY INVISIBLE (-5748 4775);
FORCEADD TAP..1
R 2
(-5750 4675);
FORCEPROP 3 LASTPIN (-5700 4675) SIG_NAME M_D_CPU1_SB_DQS_DP<3>
J 0
(-5690 4685);
DISPLAY 0.659574 (-5690 4685);
PAINT MONO (-5690 4685);
DISPLAY INVISIBLE (-5690 4685);
FORCEPROP 1 LASTPIN (-5700 4675) BN 3
J 2
(-5688 4683);
DISPLAY 0.489362 (-5688 4683);
PAINT GREEN (-5688 4683);
FORCEPROP 2 LAST CDS_LIB mstr_standard
J 2
(-5750 4675);
DISPLAY 0.723404 (-5750 4675);
PAINT MONO (-5750 4675);
DISPLAY INVISIBLE (-5750 4675);
FORCEPROP 1 LAST BODY_TYPE PLUMBING
J 2
(-5750 4725);
DISPLAY 0.872340 (-5750 4725);
PAINT GREEN (-5750 4725);
DISPLAY INVISIBLE (-5750 4725);
FORCEPROP 1 LAST HDL_TAP TRUE
J 2
(-6075 4550);
DISPLAY 0.872340 (-6075 4550);
DISPLAY INVISIBLE (-6075 4550);
FORCEPROP 1 LAST PATH I266
J 2
(-5748 4675);
DISPLAY 0.872340 (-5748 4675);
PAINT GREEN (-5748 4675);
DISPLAY INVISIBLE (-5748 4675);
FORCEADD TAP..1
R 2
(-5950 5075);
FORCEPROP 3 LASTPIN (-5900 5075) SIG_NAME M_D_CPU1_SA_DQS_DN<9>
J 0
(-5890 5085);
DISPLAY 0.659574 (-5890 5085);
PAINT MONO (-5890 5085);
DISPLAY INVISIBLE (-5890 5085);
FORCEPROP 1 LASTPIN (-5900 5075) BN 9
J 2
(-5888 5083);
DISPLAY 0.489362 (-5888 5083);
PAINT GREEN (-5888 5083);
FORCEPROP 2 LAST CDS_LIB mstr_standard
J 2
(-5950 5075);
DISPLAY 0.723404 (-5950 5075);
PAINT MONO (-5950 5075);
DISPLAY INVISIBLE (-5950 5075);
FORCEPROP 1 LAST BODY_TYPE PLUMBING
J 2
(-5950 5125);
DISPLAY 0.872340 (-5950 5125);
PAINT GREEN (-5950 5125);
DISPLAY INVISIBLE (-5950 5125);
FORCEPROP 1 LAST HDL_TAP TRUE
J 2
(-6275 4950);
DISPLAY 0.872340 (-6275 4950);
DISPLAY INVISIBLE (-6275 4950);
FORCEPROP 1 LAST PATH I267
J 2
(-5948 5075);
DISPLAY 0.872340 (-5948 5075);
PAINT GREEN (-5948 5075);
DISPLAY INVISIBLE (-5948 5075);
FORCEADD TAP..1
R 2
(-5950 4925);
FORCEPROP 3 LASTPIN (-5900 4925) SIG_NAME M_D_CPU1_SB_DQS_DN<0>
J 0
(-5890 4935);
DISPLAY 0.659574 (-5890 4935);
PAINT MONO (-5890 4935);
DISPLAY INVISIBLE (-5890 4935);
FORCEPROP 1 LASTPIN (-5900 4925) BN 0
J 2
(-5888 4933);
DISPLAY 0.489362 (-5888 4933);
PAINT GREEN (-5888 4933);
FORCEPROP 2 LAST CDS_LIB mstr_standard
J 2
(-5950 4925);
DISPLAY 0.723404 (-5950 4925);
PAINT MONO (-5950 4925);
DISPLAY INVISIBLE (-5950 4925);
FORCEPROP 1 LAST BODY_TYPE PLUMBING
J 2
(-5950 4975);
DISPLAY 0.872340 (-5950 4975);
PAINT GREEN (-5950 4975);
DISPLAY INVISIBLE (-5950 4975);
FORCEPROP 1 LAST HDL_TAP TRUE
J 2
(-6275 4800);
DISPLAY 0.872340 (-6275 4800);
DISPLAY INVISIBLE (-6275 4800);
FORCEPROP 1 LAST PATH I268
J 2
(-5948 4925);
DISPLAY 0.872340 (-5948 4925);
PAINT GREEN (-5948 4925);
DISPLAY INVISIBLE (-5948 4925);
FORCEADD TAP..1
R 2
(-5950 4825);
FORCEPROP 3 LASTPIN (-5900 4825) SIG_NAME M_D_CPU1_SB_DQS_DN<1>
J 0
(-5890 4835);
DISPLAY 0.659574 (-5890 4835);
PAINT MONO (-5890 4835);
DISPLAY INVISIBLE (-5890 4835);
FORCEPROP 1 LASTPIN (-5900 4825) BN 1
J 2
(-5888 4833);
DISPLAY 0.489362 (-5888 4833);
PAINT GREEN (-5888 4833);
FORCEPROP 2 LAST CDS_LIB mstr_standard
J 2
(-5950 4825);
DISPLAY 0.723404 (-5950 4825);
PAINT MONO (-5950 4825);
DISPLAY INVISIBLE (-5950 4825);
FORCEPROP 1 LAST BODY_TYPE PLUMBING
J 2
(-5950 4875);
DISPLAY 0.872340 (-5950 4875);
PAINT GREEN (-5950 4875);
DISPLAY INVISIBLE (-5950 4875);
FORCEPROP 1 LAST HDL_TAP TRUE
J 2
(-6275 4700);
DISPLAY 0.872340 (-6275 4700);
DISPLAY INVISIBLE (-6275 4700);
FORCEPROP 1 LAST PATH I269
J 2
(-5948 4825);
DISPLAY 0.872340 (-5948 4825);
PAINT GREEN (-5948 4825);
DISPLAY INVISIBLE (-5948 4825);
FORCEADD TAP..1
R 2
(-5950 4725);
FORCEPROP 3 LASTPIN (-5900 4725) SIG_NAME M_D_CPU1_SB_DQS_DN<2>
J 0
(-5890 4735);
DISPLAY 0.659574 (-5890 4735);
PAINT MONO (-5890 4735);
DISPLAY INVISIBLE (-5890 4735);
FORCEPROP 1 LASTPIN (-5900 4725) BN 2
J 2
(-5888 4733);
DISPLAY 0.489362 (-5888 4733);
PAINT GREEN (-5888 4733);
FORCEPROP 2 LAST CDS_LIB mstr_standard
J 2
(-5950 4725);
DISPLAY 0.723404 (-5950 4725);
PAINT MONO (-5950 4725);
DISPLAY INVISIBLE (-5950 4725);
FORCEPROP 1 LAST BODY_TYPE PLUMBING
J 2
(-5950 4775);
DISPLAY 0.872340 (-5950 4775);
PAINT GREEN (-5950 4775);
DISPLAY INVISIBLE (-5950 4775);
FORCEPROP 1 LAST HDL_TAP TRUE
J 2
(-6275 4600);
DISPLAY 0.872340 (-6275 4600);
DISPLAY INVISIBLE (-6275 4600);
FORCEPROP 1 LAST PATH I270
J 2
(-5948 4725);
DISPLAY 0.872340 (-5948 4725);
PAINT GREEN (-5948 4725);
DISPLAY INVISIBLE (-5948 4725);
FORCEADD TAP..1
R 2
(-5950 4625);
FORCEPROP 3 LASTPIN (-5900 4625) SIG_NAME M_D_CPU1_SB_DQS_DN<3>
J 0
(-5890 4635);
DISPLAY 0.659574 (-5890 4635);
PAINT MONO (-5890 4635);
DISPLAY INVISIBLE (-5890 4635);
FORCEPROP 1 LASTPIN (-5900 4625) BN 3
J 2
(-5888 4633);
DISPLAY 0.489362 (-5888 4633);
PAINT GREEN (-5888 4633);
FORCEPROP 2 LAST CDS_LIB mstr_standard
J 2
(-5950 4625);
DISPLAY 0.723404 (-5950 4625);
PAINT MONO (-5950 4625);
DISPLAY INVISIBLE (-5950 4625);
FORCEPROP 1 LAST BODY_TYPE PLUMBING
J 2
(-5950 4675);
DISPLAY 0.872340 (-5950 4675);
PAINT GREEN (-5950 4675);
DISPLAY INVISIBLE (-5950 4675);
FORCEPROP 1 LAST HDL_TAP TRUE
J 2
(-6275 4500);
DISPLAY 0.872340 (-6275 4500);
DISPLAY INVISIBLE (-6275 4500);
FORCEPROP 1 LAST PATH I271
J 2
(-5948 4625);
DISPLAY 0.872340 (-5948 4625);
PAINT GREEN (-5948 4625);
DISPLAY INVISIBLE (-5948 4625);
FORCEADD TAP..1
R 2
(-5750 4575);
FORCEPROP 3 LASTPIN (-5700 4575) SIG_NAME M_D_CPU1_SB_DQS_DP<4>
J 0
(-5690 4585);
DISPLAY 0.659574 (-5690 4585);
PAINT MONO (-5690 4585);
DISPLAY INVISIBLE (-5690 4585);
FORCEPROP 1 LASTPIN (-5700 4575) BN 4
J 2
(-5688 4583);
DISPLAY 0.489362 (-5688 4583);
PAINT GREEN (-5688 4583);
FORCEPROP 2 LAST CDS_LIB mstr_standard
J 2
(-5750 4575);
DISPLAY 0.723404 (-5750 4575);
PAINT MONO (-5750 4575);
DISPLAY INVISIBLE (-5750 4575);
FORCEPROP 1 LAST BODY_TYPE PLUMBING
J 2
(-5750 4625);
DISPLAY 0.872340 (-5750 4625);
PAINT GREEN (-5750 4625);
DISPLAY INVISIBLE (-5750 4625);
FORCEPROP 1 LAST HDL_TAP TRUE
J 2
(-6075 4450);
DISPLAY 0.872340 (-6075 4450);
DISPLAY INVISIBLE (-6075 4450);
FORCEPROP 1 LAST PATH I272
J 2
(-5748 4575);
DISPLAY 0.872340 (-5748 4575);
PAINT GREEN (-5748 4575);
DISPLAY INVISIBLE (-5748 4575);
FORCEADD TAP..1
R 2
(-5750 4475);
FORCEPROP 3 LASTPIN (-5700 4475) SIG_NAME M_D_CPU1_SB_DQS_DP<5>
J 0
(-5690 4485);
DISPLAY 0.659574 (-5690 4485);
PAINT MONO (-5690 4485);
DISPLAY INVISIBLE (-5690 4485);
FORCEPROP 1 LASTPIN (-5700 4475) BN 5
J 2
(-5688 4483);
DISPLAY 0.489362 (-5688 4483);
PAINT GREEN (-5688 4483);
FORCEPROP 2 LAST CDS_LIB mstr_standard
J 2
(-5750 4475);
DISPLAY 0.723404 (-5750 4475);
PAINT MONO (-5750 4475);
DISPLAY INVISIBLE (-5750 4475);
FORCEPROP 1 LAST BODY_TYPE PLUMBING
J 2
(-5750 4525);
DISPLAY 0.872340 (-5750 4525);
PAINT GREEN (-5750 4525);
DISPLAY INVISIBLE (-5750 4525);
FORCEPROP 1 LAST HDL_TAP TRUE
J 2
(-6075 4350);
DISPLAY 0.872340 (-6075 4350);
DISPLAY INVISIBLE (-6075 4350);
FORCEPROP 1 LAST PATH I273
J 2
(-5748 4475);
DISPLAY 0.872340 (-5748 4475);
PAINT GREEN (-5748 4475);
DISPLAY INVISIBLE (-5748 4475);
FORCEADD TAP..1
R 2
(-5750 4375);
FORCEPROP 3 LASTPIN (-5700 4375) SIG_NAME M_D_CPU1_SB_DQS_DP<6>
J 0
(-5690 4385);
DISPLAY 0.659574 (-5690 4385);
PAINT MONO (-5690 4385);
DISPLAY INVISIBLE (-5690 4385);
FORCEPROP 1 LASTPIN (-5700 4375) BN 6
J 2
(-5688 4383);
DISPLAY 0.489362 (-5688 4383);
PAINT GREEN (-5688 4383);
FORCEPROP 2 LAST CDS_LIB mstr_standard
J 2
(-5750 4375);
DISPLAY 0.723404 (-5750 4375);
PAINT MONO (-5750 4375);
DISPLAY INVISIBLE (-5750 4375);
FORCEPROP 1 LAST BODY_TYPE PLUMBING
J 2
(-5750 4425);
DISPLAY 0.872340 (-5750 4425);
PAINT GREEN (-5750 4425);
DISPLAY INVISIBLE (-5750 4425);
FORCEPROP 1 LAST HDL_TAP TRUE
J 2
(-6075 4250);
DISPLAY 0.872340 (-6075 4250);
DISPLAY INVISIBLE (-6075 4250);
FORCEPROP 1 LAST PATH I274
J 2
(-5748 4375);
DISPLAY 0.872340 (-5748 4375);
PAINT GREEN (-5748 4375);
DISPLAY INVISIBLE (-5748 4375);
FORCEADD TAP..1
R 2
(-5750 4275);
FORCEPROP 3 LASTPIN (-5700 4275) SIG_NAME M_D_CPU1_SB_DQS_DP<7>
J 0
(-5690 4285);
DISPLAY 0.659574 (-5690 4285);
PAINT MONO (-5690 4285);
DISPLAY INVISIBLE (-5690 4285);
FORCEPROP 1 LASTPIN (-5700 4275) BN 7
J 2
(-5688 4283);
DISPLAY 0.489362 (-5688 4283);
PAINT GREEN (-5688 4283);
FORCEPROP 2 LAST CDS_LIB mstr_standard
J 2
(-5750 4275);
DISPLAY 0.723404 (-5750 4275);
PAINT MONO (-5750 4275);
DISPLAY INVISIBLE (-5750 4275);
FORCEPROP 1 LAST BODY_TYPE PLUMBING
J 2
(-5750 4325);
DISPLAY 0.872340 (-5750 4325);
PAINT GREEN (-5750 4325);
DISPLAY INVISIBLE (-5750 4325);
FORCEPROP 1 LAST HDL_TAP TRUE
J 2
(-6075 4150);
DISPLAY 0.872340 (-6075 4150);
DISPLAY INVISIBLE (-6075 4150);
FORCEPROP 1 LAST PATH I275
J 2
(-5748 4275);
DISPLAY 0.872340 (-5748 4275);
PAINT GREEN (-5748 4275);
DISPLAY INVISIBLE (-5748 4275);
FORCEADD TAP..1
R 2
(-5750 4175);
FORCEPROP 3 LASTPIN (-5700 4175) SIG_NAME M_D_CPU1_SB_DQS_DP<8>
J 0
(-5690 4185);
DISPLAY 0.659574 (-5690 4185);
PAINT MONO (-5690 4185);
DISPLAY INVISIBLE (-5690 4185);
FORCEPROP 1 LASTPIN (-5700 4175) BN 8
J 2
(-5688 4183);
DISPLAY 0.489362 (-5688 4183);
PAINT GREEN (-5688 4183);
FORCEPROP 2 LAST CDS_LIB mstr_standard
J 2
(-5750 4175);
DISPLAY 0.723404 (-5750 4175);
PAINT MONO (-5750 4175);
DISPLAY INVISIBLE (-5750 4175);
FORCEPROP 1 LAST BODY_TYPE PLUMBING
J 2
(-5750 4225);
DISPLAY 0.872340 (-5750 4225);
PAINT GREEN (-5750 4225);
DISPLAY INVISIBLE (-5750 4225);
FORCEPROP 1 LAST HDL_TAP TRUE
J 2
(-6075 4050);
DISPLAY 0.872340 (-6075 4050);
DISPLAY INVISIBLE (-6075 4050);
FORCEPROP 1 LAST PATH I276
J 2
(-5748 4175);
DISPLAY 0.872340 (-5748 4175);
PAINT GREEN (-5748 4175);
DISPLAY INVISIBLE (-5748 4175);
FORCEADD TAP..1
R 2
(-5950 4525);
FORCEPROP 3 LASTPIN (-5900 4525) SIG_NAME M_D_CPU1_SB_DQS_DN<4>
J 0
(-5890 4535);
DISPLAY 0.659574 (-5890 4535);
PAINT MONO (-5890 4535);
DISPLAY INVISIBLE (-5890 4535);
FORCEPROP 1 LASTPIN (-5900 4525) BN 4
J 2
(-5888 4533);
DISPLAY 0.489362 (-5888 4533);
PAINT GREEN (-5888 4533);
FORCEPROP 2 LAST CDS_LIB mstr_standard
J 2
(-5950 4525);
DISPLAY 0.723404 (-5950 4525);
PAINT MONO (-5950 4525);
DISPLAY INVISIBLE (-5950 4525);
FORCEPROP 1 LAST BODY_TYPE PLUMBING
J 2
(-5950 4575);
DISPLAY 0.872340 (-5950 4575);
PAINT GREEN (-5950 4575);
DISPLAY INVISIBLE (-5950 4575);
FORCEPROP 1 LAST HDL_TAP TRUE
J 2
(-6275 4400);
DISPLAY 0.872340 (-6275 4400);
DISPLAY INVISIBLE (-6275 4400);
FORCEPROP 1 LAST PATH I277
J 2
(-5948 4525);
DISPLAY 0.872340 (-5948 4525);
PAINT GREEN (-5948 4525);
DISPLAY INVISIBLE (-5948 4525);
FORCEADD TAP..1
R 2
(-5950 4425);
FORCEPROP 3 LASTPIN (-5900 4425) SIG_NAME M_D_CPU1_SB_DQS_DN<5>
J 0
(-5890 4435);
DISPLAY 0.659574 (-5890 4435);
PAINT MONO (-5890 4435);
DISPLAY INVISIBLE (-5890 4435);
FORCEPROP 1 LASTPIN (-5900 4425) BN 5
J 2
(-5888 4433);
DISPLAY 0.489362 (-5888 4433);
PAINT GREEN (-5888 4433);
FORCEPROP 2 LAST CDS_LIB mstr_standard
J 2
(-5950 4425);
DISPLAY 0.723404 (-5950 4425);
PAINT MONO (-5950 4425);
DISPLAY INVISIBLE (-5950 4425);
FORCEPROP 1 LAST BODY_TYPE PLUMBING
J 2
(-5950 4475);
DISPLAY 0.872340 (-5950 4475);
PAINT GREEN (-5950 4475);
DISPLAY INVISIBLE (-5950 4475);
FORCEPROP 1 LAST HDL_TAP TRUE
J 2
(-6275 4300);
DISPLAY 0.872340 (-6275 4300);
DISPLAY INVISIBLE (-6275 4300);
FORCEPROP 1 LAST PATH I278
J 2
(-5948 4425);
DISPLAY 0.872340 (-5948 4425);
PAINT GREEN (-5948 4425);
DISPLAY INVISIBLE (-5948 4425);
FORCEADD TAP..1
R 2
(-5950 4325);
FORCEPROP 3 LASTPIN (-5900 4325) SIG_NAME M_D_CPU1_SB_DQS_DN<6>
J 0
(-5890 4335);
DISPLAY 0.659574 (-5890 4335);
PAINT MONO (-5890 4335);
DISPLAY INVISIBLE (-5890 4335);
FORCEPROP 1 LASTPIN (-5900 4325) BN 6
J 2
(-5888 4333);
DISPLAY 0.489362 (-5888 4333);
PAINT GREEN (-5888 4333);
FORCEPROP 2 LAST CDS_LIB mstr_standard
J 2
(-5950 4325);
DISPLAY 0.723404 (-5950 4325);
PAINT MONO (-5950 4325);
DISPLAY INVISIBLE (-5950 4325);
FORCEPROP 1 LAST BODY_TYPE PLUMBING
J 2
(-5950 4375);
DISPLAY 0.872340 (-5950 4375);
PAINT GREEN (-5950 4375);
DISPLAY INVISIBLE (-5950 4375);
FORCEPROP 1 LAST HDL_TAP TRUE
J 2
(-6275 4200);
DISPLAY 0.872340 (-6275 4200);
DISPLAY INVISIBLE (-6275 4200);
FORCEPROP 1 LAST PATH I279
J 2
(-5948 4325);
DISPLAY 0.872340 (-5948 4325);
PAINT GREEN (-5948 4325);
DISPLAY INVISIBLE (-5948 4325);
FORCEADD TAP..1
R 2
(-5950 4225);
FORCEPROP 3 LASTPIN (-5900 4225) SIG_NAME M_D_CPU1_SB_DQS_DN<7>
J 0
(-5890 4235);
DISPLAY 0.659574 (-5890 4235);
PAINT MONO (-5890 4235);
DISPLAY INVISIBLE (-5890 4235);
FORCEPROP 1 LASTPIN (-5900 4225) BN 7
J 2
(-5888 4233);
DISPLAY 0.489362 (-5888 4233);
PAINT GREEN (-5888 4233);
FORCEPROP 2 LAST CDS_LIB mstr_standard
J 2
(-5950 4225);
DISPLAY 0.723404 (-5950 4225);
PAINT MONO (-5950 4225);
DISPLAY INVISIBLE (-5950 4225);
FORCEPROP 1 LAST BODY_TYPE PLUMBING
J 2
(-5950 4275);
DISPLAY 0.872340 (-5950 4275);
PAINT GREEN (-5950 4275);
DISPLAY INVISIBLE (-5950 4275);
FORCEPROP 1 LAST HDL_TAP TRUE
J 2
(-6275 4100);
DISPLAY 0.872340 (-6275 4100);
DISPLAY INVISIBLE (-6275 4100);
FORCEPROP 1 LAST PATH I280
J 2
(-5948 4225);
DISPLAY 0.872340 (-5948 4225);
PAINT GREEN (-5948 4225);
DISPLAY INVISIBLE (-5948 4225);
FORCEADD TAP..1
R 2
(-5950 4125);
FORCEPROP 3 LASTPIN (-5900 4125) SIG_NAME M_D_CPU1_SB_DQS_DN<8>
J 0
(-5890 4135);
DISPLAY 0.659574 (-5890 4135);
PAINT MONO (-5890 4135);
DISPLAY INVISIBLE (-5890 4135);
FORCEPROP 1 LASTPIN (-5900 4125) BN 8
J 2
(-5888 4133);
DISPLAY 0.489362 (-5888 4133);
PAINT GREEN (-5888 4133);
FORCEPROP 2 LAST CDS_LIB mstr_standard
J 2
(-5950 4125);
DISPLAY 0.723404 (-5950 4125);
PAINT MONO (-5950 4125);
DISPLAY INVISIBLE (-5950 4125);
FORCEPROP 1 LAST BODY_TYPE PLUMBING
J 2
(-5950 4175);
DISPLAY 0.872340 (-5950 4175);
PAINT GREEN (-5950 4175);
DISPLAY INVISIBLE (-5950 4175);
FORCEPROP 1 LAST HDL_TAP TRUE
J 2
(-6275 4000);
DISPLAY 0.872340 (-6275 4000);
DISPLAY INVISIBLE (-6275 4000);
FORCEPROP 1 LAST PATH I281
J 2
(-5948 4125);
DISPLAY 0.872340 (-5948 4125);
PAINT GREEN (-5948 4125);
DISPLAY INVISIBLE (-5948 4125);
FORCEADD OFFPAGE..3
R 2
(-6650 6050);
FORCEPROP 2 LAST $XR0 100 
J 0
(-6930 6050);
DISPLAY 0.638298 (-6930 6050);
PAINT MONO (-6930 6050);
FORCEPROP 2 LAST PATH I282
J 0
(-6925 6100);
DISPLAY 1.021277 (-6925 6100);
DISPLAY INVISIBLE (-6925 6100);
FORCEPROP 1 LAST COMMENT_BODY TRUE
J 2
(-6600 5950);
DISPLAY 0.872340 (-6600 5950);
PAINT GREEN (-6600 5950);
DISPLAY INVISIBLE (-6600 5950);
FORCEPROP 1 LAST OFFPAGE TRUE
J 2
(-6975 5925);
DISPLAY 0.872340 (-6975 5925);
PAINT GREEN (-6975 5925);
DISPLAY INVISIBLE (-6975 5925);
FORCEPROP 2 LAST CDS_LIB standard
J 0
(-6650 6050);
DISPLAY INVISIBLE (-6650 6050);
FORCEADD OFFPAGE..3
R 2
(-6650 6000);
FORCEPROP 2 LAST $XR0 100 
J 0
(-6930 6000);
DISPLAY 0.638298 (-6930 6000);
PAINT MONO (-6930 6000);
FORCEPROP 2 LAST PATH I283
J 0
(-6925 6050);
DISPLAY 1.021277 (-6925 6050);
DISPLAY INVISIBLE (-6925 6050);
FORCEPROP 1 LAST COMMENT_BODY TRUE
J 2
(-6600 5900);
DISPLAY 0.872340 (-6600 5900);
PAINT GREEN (-6600 5900);
DISPLAY INVISIBLE (-6600 5900);
FORCEPROP 1 LAST OFFPAGE TRUE
J 2
(-6975 5875);
DISPLAY 0.872340 (-6975 5875);
PAINT GREEN (-6975 5875);
DISPLAY INVISIBLE (-6975 5875);
FORCEPROP 2 LAST CDS_LIB standard
J 0
(-6650 6000);
DISPLAY INVISIBLE (-6650 6000);
FORCEADD OFFPAGE..3
R 2
(-6650 5000);
FORCEPROP 2 LAST $XR0 100 
J 0
(-6930 5000);
DISPLAY 0.638298 (-6930 5000);
PAINT MONO (-6930 5000);
FORCEPROP 2 LAST PATH I284
J 0
(-6925 5050);
DISPLAY 1.021277 (-6925 5050);
DISPLAY INVISIBLE (-6925 5050);
FORCEPROP 1 LAST COMMENT_BODY TRUE
J 2
(-6600 4900);
DISPLAY 0.872340 (-6600 4900);
PAINT GREEN (-6600 4900);
DISPLAY INVISIBLE (-6600 4900);
FORCEPROP 1 LAST OFFPAGE TRUE
J 2
(-6975 4875);
DISPLAY 0.872340 (-6975 4875);
PAINT GREEN (-6975 4875);
DISPLAY INVISIBLE (-6975 4875);
FORCEPROP 2 LAST CDS_LIB standard
J 0
(-6650 5000);
DISPLAY INVISIBLE (-6650 5000);
FORCEADD OFFPAGE..3
R 2
(-6650 4950);
FORCEPROP 2 LAST $XR0 100 
J 0
(-6930 4950);
DISPLAY 0.638298 (-6930 4950);
PAINT MONO (-6930 4950);
FORCEPROP 2 LAST PATH I285
J 0
(-6925 5000);
DISPLAY 1.021277 (-6925 5000);
DISPLAY INVISIBLE (-6925 5000);
FORCEPROP 1 LAST COMMENT_BODY TRUE
J 2
(-6600 4850);
DISPLAY 0.872340 (-6600 4850);
PAINT GREEN (-6600 4850);
DISPLAY INVISIBLE (-6600 4850);
FORCEPROP 1 LAST OFFPAGE TRUE
J 2
(-6975 4825);
DISPLAY 0.872340 (-6975 4825);
PAINT GREEN (-6975 4825);
DISPLAY INVISIBLE (-6975 4825);
FORCEPROP 2 LAST CDS_LIB standard
J 0
(-6650 4950);
DISPLAY INVISIBLE (-6650 4950);
FORCEADD TAP..1
R 2
(-5750 4075);
FORCEPROP 3 LASTPIN (-5700 4075) SIG_NAME M_D_CPU1_SB_DQS_DP<9>
J 0
(-5690 4085);
DISPLAY 0.659574 (-5690 4085);
PAINT MONO (-5690 4085);
DISPLAY INVISIBLE (-5690 4085);
FORCEPROP 1 LASTPIN (-5700 4075) BN 9
J 2
(-5688 4083);
DISPLAY 0.489362 (-5688 4083);
PAINT GREEN (-5688 4083);
FORCEPROP 2 LAST CDS_LIB mstr_standard
J 2
(-5750 4075);
DISPLAY 0.723404 (-5750 4075);
PAINT MONO (-5750 4075);
DISPLAY INVISIBLE (-5750 4075);
FORCEPROP 1 LAST BODY_TYPE PLUMBING
J 2
(-5750 4125);
DISPLAY 0.872340 (-5750 4125);
PAINT GREEN (-5750 4125);
DISPLAY INVISIBLE (-5750 4125);
FORCEPROP 1 LAST HDL_TAP TRUE
J 2
(-6075 3950);
DISPLAY 0.872340 (-6075 3950);
DISPLAY INVISIBLE (-6075 3950);
FORCEPROP 1 LAST PATH I286
J 2
(-5748 4075);
DISPLAY 0.872340 (-5748 4075);
PAINT GREEN (-5748 4075);
DISPLAY INVISIBLE (-5748 4075);
FORCEADD TAP..1
R 2
(-5950 4025);
FORCEPROP 3 LASTPIN (-5900 4025) SIG_NAME M_D_CPU1_SB_DQS_DN<9>
J 0
(-5890 4035);
DISPLAY 0.659574 (-5890 4035);
PAINT MONO (-5890 4035);
DISPLAY INVISIBLE (-5890 4035);
FORCEPROP 1 LASTPIN (-5900 4025) BN 9
J 2
(-5888 4033);
DISPLAY 0.489362 (-5888 4033);
PAINT GREEN (-5888 4033);
FORCEPROP 2 LAST CDS_LIB mstr_standard
J 2
(-5950 4025);
DISPLAY 0.723404 (-5950 4025);
PAINT MONO (-5950 4025);
DISPLAY INVISIBLE (-5950 4025);
FORCEPROP 1 LAST BODY_TYPE PLUMBING
J 2
(-5950 4075);
DISPLAY 0.872340 (-5950 4075);
PAINT GREEN (-5950 4075);
DISPLAY INVISIBLE (-5950 4075);
FORCEPROP 1 LAST HDL_TAP TRUE
J 2
(-6275 3900);
DISPLAY 0.872340 (-6275 3900);
DISPLAY INVISIBLE (-6275 3900);
FORCEPROP 1 LAST PATH I287
J 2
(-5948 4025);
DISPLAY 0.872340 (-5948 4025);
PAINT GREEN (-5948 4025);
DISPLAY INVISIBLE (-5948 4025);
FORCEADD TAP..1
R 2
(-5950 3825);
FORCEPROP 3 LASTPIN (-5900 3825) SIG_NAME M_D_CPU1_SA_CA<1>
J 0
(-5890 3835);
DISPLAY 0.659574 (-5890 3835);
PAINT MONO (-5890 3835);
DISPLAY INVISIBLE (-5890 3835);
FORCEPROP 1 LASTPIN (-5900 3825) BN 1
J 2
(-5888 3833);
DISPLAY 0.489362 (-5888 3833);
PAINT GREEN (-5888 3833);
FORCEPROP 2 LAST CDS_LIB mstr_standard
J 0
(-5950 3825);
DISPLAY 0.723404 (-5950 3825);
PAINT MONO (-5950 3825);
DISPLAY INVISIBLE (-5950 3825);
FORCEPROP 1 LAST BODY_TYPE PLUMBING
J 2
(-5950 3875);
DISPLAY 0.872340 (-5950 3875);
PAINT GREEN (-5950 3875);
DISPLAY INVISIBLE (-5950 3875);
FORCEPROP 1 LAST HDL_TAP TRUE
J 2
(-6275 3700);
DISPLAY 0.872340 (-6275 3700);
DISPLAY INVISIBLE (-6275 3700);
FORCEPROP 1 LAST PATH I288
J 2
(-5948 3825);
DISPLAY 0.872340 (-5948 3825);
PAINT GREEN (-5948 3825);
DISPLAY INVISIBLE (-5948 3825);
FORCEADD TAP..1
R 2
(-5950 3875);
FORCEPROP 3 LASTPIN (-5900 3875) SIG_NAME M_D_CPU1_SA_CA<0>
J 0
(-5890 3885);
DISPLAY 0.659574 (-5890 3885);
PAINT MONO (-5890 3885);
DISPLAY INVISIBLE (-5890 3885);
FORCEPROP 1 LASTPIN (-5900 3875) BN 0
J 2
(-5888 3883);
DISPLAY 0.489362 (-5888 3883);
PAINT GREEN (-5888 3883);
FORCEPROP 2 LAST CDS_LIB mstr_standard
J 0
(-5950 3875);
DISPLAY 0.723404 (-5950 3875);
PAINT MONO (-5950 3875);
DISPLAY INVISIBLE (-5950 3875);
FORCEPROP 1 LAST BODY_TYPE PLUMBING
J 2
(-5950 3925);
DISPLAY 0.872340 (-5950 3925);
PAINT GREEN (-5950 3925);
DISPLAY INVISIBLE (-5950 3925);
FORCEPROP 1 LAST HDL_TAP TRUE
J 2
(-6275 3750);
DISPLAY 0.872340 (-6275 3750);
DISPLAY INVISIBLE (-6275 3750);
FORCEPROP 1 LAST PATH I289
J 2
(-5948 3875);
DISPLAY 0.872340 (-5948 3875);
PAINT GREEN (-5948 3875);
DISPLAY INVISIBLE (-5948 3875);
FORCEADD TAP..1
R 2
(-5950 3775);
FORCEPROP 3 LASTPIN (-5900 3775) SIG_NAME M_D_CPU1_SA_CA<2>
J 0
(-5890 3785);
DISPLAY 0.659574 (-5890 3785);
PAINT MONO (-5890 3785);
DISPLAY INVISIBLE (-5890 3785);
FORCEPROP 1 LASTPIN (-5900 3775) BN 2
J 2
(-5888 3783);
DISPLAY 0.489362 (-5888 3783);
PAINT GREEN (-5888 3783);
FORCEPROP 2 LAST CDS_LIB mstr_standard
J 0
(-5950 3775);
DISPLAY 0.723404 (-5950 3775);
PAINT MONO (-5950 3775);
DISPLAY INVISIBLE (-5950 3775);
FORCEPROP 1 LAST BODY_TYPE PLUMBING
J 2
(-5950 3825);
DISPLAY 0.872340 (-5950 3825);
PAINT GREEN (-5950 3825);
DISPLAY INVISIBLE (-5950 3825);
FORCEPROP 1 LAST HDL_TAP TRUE
J 2
(-6275 3650);
DISPLAY 0.872340 (-6275 3650);
DISPLAY INVISIBLE (-6275 3650);
FORCEPROP 1 LAST PATH I290
J 2
(-5948 3775);
DISPLAY 0.872340 (-5948 3775);
PAINT GREEN (-5948 3775);
DISPLAY INVISIBLE (-5948 3775);
FORCEADD TAP..1
R 2
(-5950 3725);
FORCEPROP 3 LASTPIN (-5900 3725) SIG_NAME M_D_CPU1_SA_CA<3>
J 0
(-5890 3735);
DISPLAY 0.659574 (-5890 3735);
PAINT MONO (-5890 3735);
DISPLAY INVISIBLE (-5890 3735);
FORCEPROP 1 LASTPIN (-5900 3725) BN 3
J 2
(-5888 3733);
DISPLAY 0.489362 (-5888 3733);
PAINT GREEN (-5888 3733);
FORCEPROP 2 LAST CDS_LIB mstr_standard
J 0
(-5950 3725);
DISPLAY 0.723404 (-5950 3725);
PAINT MONO (-5950 3725);
DISPLAY INVISIBLE (-5950 3725);
FORCEPROP 1 LAST BODY_TYPE PLUMBING
J 2
(-5950 3775);
DISPLAY 0.872340 (-5950 3775);
PAINT GREEN (-5950 3775);
DISPLAY INVISIBLE (-5950 3775);
FORCEPROP 1 LAST HDL_TAP TRUE
J 2
(-6275 3600);
DISPLAY 0.872340 (-6275 3600);
DISPLAY INVISIBLE (-6275 3600);
FORCEPROP 1 LAST PATH I291
J 2
(-5948 3725);
DISPLAY 0.872340 (-5948 3725);
PAINT GREEN (-5948 3725);
DISPLAY INVISIBLE (-5948 3725);
FORCEADD TAP..1
R 2
(-5950 3675);
FORCEPROP 3 LASTPIN (-5900 3675) SIG_NAME M_D_CPU1_SA_CA<4>
J 0
(-5890 3685);
DISPLAY 0.659574 (-5890 3685);
PAINT MONO (-5890 3685);
DISPLAY INVISIBLE (-5890 3685);
FORCEPROP 1 LASTPIN (-5900 3675) BN 4
J 2
(-5888 3683);
DISPLAY 0.489362 (-5888 3683);
PAINT GREEN (-5888 3683);
FORCEPROP 2 LAST CDS_LIB mstr_standard
J 0
(-5950 3675);
DISPLAY 0.723404 (-5950 3675);
PAINT MONO (-5950 3675);
DISPLAY INVISIBLE (-5950 3675);
FORCEPROP 1 LAST BODY_TYPE PLUMBING
J 2
(-5950 3725);
DISPLAY 0.872340 (-5950 3725);
PAINT GREEN (-5950 3725);
DISPLAY INVISIBLE (-5950 3725);
FORCEPROP 1 LAST HDL_TAP TRUE
J 2
(-6275 3550);
DISPLAY 0.872340 (-6275 3550);
DISPLAY INVISIBLE (-6275 3550);
FORCEPROP 1 LAST PATH I292
J 2
(-5948 3675);
DISPLAY 0.872340 (-5948 3675);
PAINT GREEN (-5948 3675);
DISPLAY INVISIBLE (-5948 3675);
FORCEADD TAP..1
R 2
(-5950 3625);
FORCEPROP 3 LASTPIN (-5900 3625) SIG_NAME M_D_CPU1_SA_CA<5>
J 0
(-5890 3635);
DISPLAY 0.659574 (-5890 3635);
PAINT MONO (-5890 3635);
DISPLAY INVISIBLE (-5890 3635);
FORCEPROP 1 LASTPIN (-5900 3625) BN 5
J 2
(-5888 3633);
DISPLAY 0.489362 (-5888 3633);
PAINT GREEN (-5888 3633);
FORCEPROP 2 LAST CDS_LIB mstr_standard
J 0
(-5950 3625);
DISPLAY 0.723404 (-5950 3625);
PAINT MONO (-5950 3625);
DISPLAY INVISIBLE (-5950 3625);
FORCEPROP 1 LAST BODY_TYPE PLUMBING
J 2
(-5950 3675);
DISPLAY 0.872340 (-5950 3675);
PAINT GREEN (-5950 3675);
DISPLAY INVISIBLE (-5950 3675);
FORCEPROP 1 LAST HDL_TAP TRUE
J 2
(-6275 3500);
DISPLAY 0.872340 (-6275 3500);
DISPLAY INVISIBLE (-6275 3500);
FORCEPROP 1 LAST PATH I293
J 2
(-5948 3625);
DISPLAY 0.872340 (-5948 3625);
PAINT GREEN (-5948 3625);
DISPLAY INVISIBLE (-5948 3625);
FORCEADD TAP..1
R 2
(-5950 3575);
FORCEPROP 3 LASTPIN (-5900 3575) SIG_NAME M_D_CPU1_SA_CA<6>
J 0
(-5890 3585);
DISPLAY 0.659574 (-5890 3585);
PAINT MONO (-5890 3585);
DISPLAY INVISIBLE (-5890 3585);
FORCEPROP 1 LASTPIN (-5900 3575) BN 6
J 2
(-5888 3583);
DISPLAY 0.489362 (-5888 3583);
PAINT GREEN (-5888 3583);
FORCEPROP 2 LAST CDS_LIB mstr_standard
J 0
(-5950 3575);
DISPLAY 0.723404 (-5950 3575);
PAINT MONO (-5950 3575);
DISPLAY INVISIBLE (-5950 3575);
FORCEPROP 1 LAST BODY_TYPE PLUMBING
J 2
(-5950 3625);
DISPLAY 0.872340 (-5950 3625);
PAINT GREEN (-5950 3625);
DISPLAY INVISIBLE (-5950 3625);
FORCEPROP 1 LAST HDL_TAP TRUE
J 2
(-6275 3450);
DISPLAY 0.872340 (-6275 3450);
DISPLAY INVISIBLE (-6275 3450);
FORCEPROP 1 LAST PATH I294
J 2
(-5948 3575);
DISPLAY 0.872340 (-5948 3575);
PAINT GREEN (-5948 3575);
DISPLAY INVISIBLE (-5948 3575);
FORCEADD TAP..1
R 2
(-5950 3425);
FORCEPROP 3 LASTPIN (-5900 3425) SIG_NAME M_D_CPU1_SB_CA<1>
J 0
(-5890 3435);
DISPLAY 0.659574 (-5890 3435);
PAINT MONO (-5890 3435);
DISPLAY INVISIBLE (-5890 3435);
FORCEPROP 1 LASTPIN (-5900 3425) BN 1
J 2
(-5888 3433);
DISPLAY 0.489362 (-5888 3433);
PAINT GREEN (-5888 3433);
FORCEPROP 2 LAST CDS_LIB mstr_standard
J 0
(-5950 3425);
DISPLAY 0.723404 (-5950 3425);
PAINT MONO (-5950 3425);
DISPLAY INVISIBLE (-5950 3425);
FORCEPROP 1 LAST BODY_TYPE PLUMBING
J 2
(-5950 3475);
DISPLAY 0.872340 (-5950 3475);
PAINT GREEN (-5950 3475);
DISPLAY INVISIBLE (-5950 3475);
FORCEPROP 1 LAST HDL_TAP TRUE
J 2
(-6275 3300);
DISPLAY 0.872340 (-6275 3300);
DISPLAY INVISIBLE (-6275 3300);
FORCEPROP 1 LAST PATH I295
J 2
(-5948 3425);
DISPLAY 0.872340 (-5948 3425);
PAINT GREEN (-5948 3425);
DISPLAY INVISIBLE (-5948 3425);
FORCEADD TAP..1
R 2
(-5950 3475);
FORCEPROP 3 LASTPIN (-5900 3475) SIG_NAME M_D_CPU1_SB_CA<0>
J 0
(-5890 3485);
DISPLAY 0.659574 (-5890 3485);
PAINT MONO (-5890 3485);
DISPLAY INVISIBLE (-5890 3485);
FORCEPROP 1 LASTPIN (-5900 3475) BN 0
J 2
(-5888 3483);
DISPLAY 0.489362 (-5888 3483);
PAINT GREEN (-5888 3483);
FORCEPROP 2 LAST CDS_LIB mstr_standard
J 0
(-5950 3475);
DISPLAY 0.723404 (-5950 3475);
PAINT MONO (-5950 3475);
DISPLAY INVISIBLE (-5950 3475);
FORCEPROP 1 LAST BODY_TYPE PLUMBING
J 2
(-5950 3525);
DISPLAY 0.872340 (-5950 3525);
PAINT GREEN (-5950 3525);
DISPLAY INVISIBLE (-5950 3525);
FORCEPROP 1 LAST HDL_TAP TRUE
J 2
(-6275 3350);
DISPLAY 0.872340 (-6275 3350);
DISPLAY INVISIBLE (-6275 3350);
FORCEPROP 1 LAST PATH I296
J 2
(-5948 3475);
DISPLAY 0.872340 (-5948 3475);
PAINT GREEN (-5948 3475);
DISPLAY INVISIBLE (-5948 3475);
FORCEADD TAP..1
R 2
(-5950 3325);
FORCEPROP 3 LASTPIN (-5900 3325) SIG_NAME M_D_CPU1_SB_CA<3>
J 0
(-5890 3335);
DISPLAY 0.659574 (-5890 3335);
PAINT MONO (-5890 3335);
DISPLAY INVISIBLE (-5890 3335);
FORCEPROP 1 LASTPIN (-5900 3325) BN 3
J 2
(-5888 3333);
DISPLAY 0.489362 (-5888 3333);
PAINT GREEN (-5888 3333);
FORCEPROP 2 LAST CDS_LIB mstr_standard
J 0
(-5950 3325);
DISPLAY 0.723404 (-5950 3325);
PAINT MONO (-5950 3325);
DISPLAY INVISIBLE (-5950 3325);
FORCEPROP 1 LAST BODY_TYPE PLUMBING
J 2
(-5950 3375);
DISPLAY 0.872340 (-5950 3375);
PAINT GREEN (-5950 3375);
DISPLAY INVISIBLE (-5950 3375);
FORCEPROP 1 LAST HDL_TAP TRUE
J 2
(-6275 3200);
DISPLAY 0.872340 (-6275 3200);
DISPLAY INVISIBLE (-6275 3200);
FORCEPROP 1 LAST PATH I297
J 2
(-5948 3325);
DISPLAY 0.872340 (-5948 3325);
PAINT GREEN (-5948 3325);
DISPLAY INVISIBLE (-5948 3325);
FORCEADD TAP..1
R 2
(-5950 3375);
FORCEPROP 3 LASTPIN (-5900 3375) SIG_NAME M_D_CPU1_SB_CA<2>
J 0
(-5890 3385);
DISPLAY 0.659574 (-5890 3385);
PAINT MONO (-5890 3385);
DISPLAY INVISIBLE (-5890 3385);
FORCEPROP 1 LASTPIN (-5900 3375) BN 2
J 2
(-5888 3383);
DISPLAY 0.489362 (-5888 3383);
PAINT GREEN (-5888 3383);
FORCEPROP 2 LAST CDS_LIB mstr_standard
J 0
(-5950 3375);
DISPLAY 0.723404 (-5950 3375);
PAINT MONO (-5950 3375);
DISPLAY INVISIBLE (-5950 3375);
FORCEPROP 1 LAST BODY_TYPE PLUMBING
J 2
(-5950 3425);
DISPLAY 0.872340 (-5950 3425);
PAINT GREEN (-5950 3425);
DISPLAY INVISIBLE (-5950 3425);
FORCEPROP 1 LAST HDL_TAP TRUE
J 2
(-6275 3250);
DISPLAY 0.872340 (-6275 3250);
DISPLAY INVISIBLE (-6275 3250);
FORCEPROP 1 LAST PATH I298
J 2
(-5948 3375);
DISPLAY 0.872340 (-5948 3375);
PAINT GREEN (-5948 3375);
DISPLAY INVISIBLE (-5948 3375);
FORCEADD TAP..1
R 2
(-5950 3275);
FORCEPROP 3 LASTPIN (-5900 3275) SIG_NAME M_D_CPU1_SB_CA<4>
J 0
(-5890 3285);
DISPLAY 0.659574 (-5890 3285);
PAINT MONO (-5890 3285);
DISPLAY INVISIBLE (-5890 3285);
FORCEPROP 1 LASTPIN (-5900 3275) BN 4
J 2
(-5888 3283);
DISPLAY 0.489362 (-5888 3283);
PAINT GREEN (-5888 3283);
FORCEPROP 2 LAST CDS_LIB mstr_standard
J 0
(-5950 3275);
DISPLAY 0.723404 (-5950 3275);
PAINT MONO (-5950 3275);
DISPLAY INVISIBLE (-5950 3275);
FORCEPROP 1 LAST BODY_TYPE PLUMBING
J 2
(-5950 3325);
DISPLAY 0.872340 (-5950 3325);
PAINT GREEN (-5950 3325);
DISPLAY INVISIBLE (-5950 3325);
FORCEPROP 1 LAST HDL_TAP TRUE
J 2
(-6275 3150);
DISPLAY 0.872340 (-6275 3150);
DISPLAY INVISIBLE (-6275 3150);
FORCEPROP 1 LAST PATH I299
J 2
(-5948 3275);
DISPLAY 0.872340 (-5948 3275);
PAINT GREEN (-5948 3275);
DISPLAY INVISIBLE (-5948 3275);
FORCEADD TAP..1
R 2
(-5950 3225);
FORCEPROP 3 LASTPIN (-5900 3225) SIG_NAME M_D_CPU1_SB_CA<5>
J 0
(-5890 3235);
DISPLAY 0.659574 (-5890 3235);
PAINT MONO (-5890 3235);
DISPLAY INVISIBLE (-5890 3235);
FORCEPROP 1 LASTPIN (-5900 3225) BN 5
J 2
(-5888 3233);
DISPLAY 0.489362 (-5888 3233);
PAINT GREEN (-5888 3233);
FORCEPROP 2 LAST CDS_LIB mstr_standard
J 0
(-5950 3225);
DISPLAY 0.723404 (-5950 3225);
PAINT MONO (-5950 3225);
DISPLAY INVISIBLE (-5950 3225);
FORCEPROP 1 LAST BODY_TYPE PLUMBING
J 2
(-5950 3275);
DISPLAY 0.872340 (-5950 3275);
PAINT GREEN (-5950 3275);
DISPLAY INVISIBLE (-5950 3275);
FORCEPROP 1 LAST HDL_TAP TRUE
J 2
(-6275 3100);
DISPLAY 0.872340 (-6275 3100);
DISPLAY INVISIBLE (-6275 3100);
FORCEPROP 1 LAST PATH I300
J 2
(-5948 3225);
DISPLAY 0.872340 (-5948 3225);
PAINT GREEN (-5948 3225);
DISPLAY INVISIBLE (-5948 3225);
FORCEADD TAP..1
R 2
(-5950 3175);
FORCEPROP 3 LASTPIN (-5900 3175) SIG_NAME M_D_CPU1_SB_CA<6>
J 0
(-5890 3185);
DISPLAY 0.659574 (-5890 3185);
PAINT MONO (-5890 3185);
DISPLAY INVISIBLE (-5890 3185);
FORCEPROP 1 LASTPIN (-5900 3175) BN 6
J 2
(-5888 3183);
DISPLAY 0.489362 (-5888 3183);
PAINT GREEN (-5888 3183);
FORCEPROP 2 LAST CDS_LIB mstr_standard
J 0
(-5950 3175);
DISPLAY 0.723404 (-5950 3175);
PAINT MONO (-5950 3175);
DISPLAY INVISIBLE (-5950 3175);
FORCEPROP 1 LAST BODY_TYPE PLUMBING
J 2
(-5950 3225);
DISPLAY 0.872340 (-5950 3225);
PAINT GREEN (-5950 3225);
DISPLAY INVISIBLE (-5950 3225);
FORCEPROP 1 LAST HDL_TAP TRUE
J 2
(-6275 3050);
DISPLAY 0.872340 (-6275 3050);
DISPLAY INVISIBLE (-6275 3050);
FORCEPROP 1 LAST PATH I301
J 2
(-5948 3175);
DISPLAY 0.872340 (-5948 3175);
PAINT GREEN (-5948 3175);
DISPLAY INVISIBLE (-5948 3175);
FORCEADD OFFPAGE..2
R 2
(-6550 3900);
FORCEPROP 2 LAST $XR0 100 
J 0
(-6805 3900);
DISPLAY 0.638298 (-6805 3900);
PAINT MONO (-6805 3900);
FORCEPROP 2 LAST PATH I302
J 0
(-6800 3950);
DISPLAY 1.021277 (-6800 3950);
DISPLAY INVISIBLE (-6800 3950);
FORCEPROP 1 LAST COMMENT_BODY TRUE
J 2
(-6505 3805);
DISPLAY 0.872340 (-6505 3805);
PAINT GREEN (-6505 3805);
DISPLAY INVISIBLE (-6505 3805);
FORCEPROP 1 LAST OFFPAGE TRUE
J 2
(-6875 3775);
DISPLAY 0.872340 (-6875 3775);
PAINT GREEN (-6875 3775);
DISPLAY INVISIBLE (-6875 3775);
FORCEPROP 2 LAST CDS_LIB standard
J 0
(-6550 3900);
DISPLAY INVISIBLE (-6550 3900);
FORCEADD OFFPAGE..2
R 2
(-6550 3500);
FORCEPROP 2 LAST $XR0 100 
J 0
(-6805 3500);
DISPLAY 0.638298 (-6805 3500);
PAINT MONO (-6805 3500);
FORCEPROP 2 LAST PATH I303
J 0
(-6800 3550);
DISPLAY 1.021277 (-6800 3550);
DISPLAY INVISIBLE (-6800 3550);
FORCEPROP 1 LAST COMMENT_BODY TRUE
J 2
(-6505 3405);
DISPLAY 0.872340 (-6505 3405);
PAINT GREEN (-6505 3405);
DISPLAY INVISIBLE (-6505 3405);
FORCEPROP 1 LAST OFFPAGE TRUE
J 2
(-6875 3375);
DISPLAY 0.872340 (-6875 3375);
PAINT GREEN (-6875 3375);
DISPLAY INVISIBLE (-6875 3375);
FORCEPROP 2 LAST CDS_LIB standard
J 0
(-6550 3500);
DISPLAY INVISIBLE (-6550 3500);
FORCEADD OFFPAGE..2
R 2
(-6550 3025);
FORCEPROP 2 LAST $XR0 100 
J 0
(-6805 3025);
DISPLAY 0.638298 (-6805 3025);
PAINT MONO (-6805 3025);
FORCEPROP 2 LAST PATH I304
J 0
(-6800 3075);
DISPLAY 1.021277 (-6800 3075);
DISPLAY INVISIBLE (-6800 3075);
FORCEPROP 1 LAST COMMENT_BODY TRUE
J 2
(-6505 2930);
DISPLAY 0.872340 (-6505 2930);
PAINT GREEN (-6505 2930);
DISPLAY INVISIBLE (-6505 2930);
FORCEPROP 1 LAST OFFPAGE TRUE
J 2
(-6875 2900);
DISPLAY 0.872340 (-6875 2900);
PAINT GREEN (-6875 2900);
DISPLAY INVISIBLE (-6875 2900);
FORCEPROP 2 LAST CDS_LIB standard
J 0
(-6550 3025);
DISPLAY INVISIBLE (-6550 3025);
FORCEADD OFFPAGE..2
R 2
(-6550 2975);
FORCEPROP 2 LAST $XR0 100 
J 0
(-6805 2975);
DISPLAY 0.638298 (-6805 2975);
PAINT MONO (-6805 2975);
FORCEPROP 2 LAST PATH I305
J 0
(-6800 3025);
DISPLAY 1.021277 (-6800 3025);
DISPLAY INVISIBLE (-6800 3025);
FORCEPROP 1 LAST COMMENT_BODY TRUE
J 2
(-6505 2880);
DISPLAY 0.872340 (-6505 2880);
PAINT GREEN (-6505 2880);
DISPLAY INVISIBLE (-6505 2880);
FORCEPROP 1 LAST OFFPAGE TRUE
J 2
(-6875 2850);
DISPLAY 0.872340 (-6875 2850);
PAINT GREEN (-6875 2850);
DISPLAY INVISIBLE (-6875 2850);
FORCEPROP 2 LAST CDS_LIB standard
J 0
(-6550 2975);
DISPLAY INVISIBLE (-6550 2975);
FORCEADD OFFPAGE..2
R 2
(-6550 2875);
FORCEPROP 2 LAST $XR0 100 
J 0
(-6805 2875);
DISPLAY 0.638298 (-6805 2875);
PAINT MONO (-6805 2875);
FORCEPROP 2 LAST PATH I306
J 0
(-6800 2925);
DISPLAY 1.021277 (-6800 2925);
DISPLAY INVISIBLE (-6800 2925);
FORCEPROP 1 LAST COMMENT_BODY TRUE
J 2
(-6505 2780);
DISPLAY 0.872340 (-6505 2780);
PAINT GREEN (-6505 2780);
DISPLAY INVISIBLE (-6505 2780);
FORCEPROP 1 LAST OFFPAGE TRUE
J 2
(-6875 2750);
DISPLAY 0.872340 (-6875 2750);
PAINT GREEN (-6875 2750);
DISPLAY INVISIBLE (-6875 2750);
FORCEPROP 2 LAST CDS_LIB standard
J 0
(-6550 2875);
DISPLAY INVISIBLE (-6550 2875);
FORCEADD OFFPAGE..2
R 2
(-6550 2825);
FORCEPROP 2 LAST $XR0 100 
J 0
(-6805 2825);
DISPLAY 0.638298 (-6805 2825);
PAINT MONO (-6805 2825);
FORCEPROP 2 LAST PATH I307
J 0
(-6800 2875);
DISPLAY 1.021277 (-6800 2875);
DISPLAY INVISIBLE (-6800 2875);
FORCEPROP 1 LAST COMMENT_BODY TRUE
J 2
(-6505 2730);
DISPLAY 0.872340 (-6505 2730);
PAINT GREEN (-6505 2730);
DISPLAY INVISIBLE (-6505 2730);
FORCEPROP 1 LAST OFFPAGE TRUE
J 2
(-6875 2700);
DISPLAY 0.872340 (-6875 2700);
PAINT GREEN (-6875 2700);
DISPLAY INVISIBLE (-6875 2700);
FORCEPROP 2 LAST CDS_LIB standard
J 0
(-6550 2825);
DISPLAY INVISIBLE (-6550 2825);
FORCEADD OFFPAGE..1
(-6550 2725);
FORCEPROP 2 LAST $XR0 100 
J 0
(-6832 2725);
DISPLAY 0.638298 (-6832 2725);
PAINT MONO (-6832 2725);
FORCEPROP 2 LAST PATH I308
J 0
(-6825 2775);
DISPLAY 1.021277 (-6825 2775);
DISPLAY INVISIBLE (-6825 2775);
FORCEPROP 1 LAST COMMENT_BODY TRUE
J 0
(-6425 2625);
DISPLAY 0.872340 (-6425 2625);
PAINT GREEN (-6425 2625);
DISPLAY INVISIBLE (-6425 2625);
FORCEPROP 1 LAST OFFPAGE TRUE
J 0
(-6225 2600);
DISPLAY 0.872340 (-6225 2600);
PAINT GREEN (-6225 2600);
DISPLAY INVISIBLE (-6225 2600);
FORCEPROP 2 LAST CDS_LIB standard
J 0
(-6550 2725);
DISPLAY INVISIBLE (-6550 2725);
FORCEADD OFFPAGE..5
(-6550 2625);
FORCEPROP 2 LAST $XR0 100 
J 0
(-6805 2625);
DISPLAY 0.638298 (-6805 2625);
PAINT MONO (-6805 2625);
FORCEPROP 2 LAST PATH I309
J 0
(-6800 2675);
DISPLAY 1.021277 (-6800 2675);
DISPLAY INVISIBLE (-6800 2675);
FORCEPROP 1 LAST COMMENT_BODY TRUE
J 0
(-6450 2550);
DISPLAY 0.872340 (-6450 2550);
PAINT GREEN (-6450 2550);
DISPLAY INVISIBLE (-6450 2550);
FORCEPROP 1 LAST OFFPAGE TRUE
J 0
(-6225 2500);
DISPLAY 0.872340 (-6225 2500);
PAINT GREEN (-6225 2500);
DISPLAY INVISIBLE (-6225 2500);
FORCEPROP 2 LAST CDS_LIB mstr_standard
J 0
(-6550 2625);
DISPLAY INVISIBLE (-6550 2625);
FORCEADD OFFPAGE..2
R 2
(-6550 2525);
FORCEPROP 2 LAST $XR0 100 
J 0
(-6805 2525);
DISPLAY 0.638298 (-6805 2525);
PAINT MONO (-6805 2525);
FORCEPROP 2 LAST PATH I310
J 0
(-6800 2575);
DISPLAY 1.021277 (-6800 2575);
DISPLAY INVISIBLE (-6800 2575);
FORCEPROP 1 LAST COMMENT_BODY TRUE
J 2
(-6505 2430);
DISPLAY 0.872340 (-6505 2430);
PAINT GREEN (-6505 2430);
DISPLAY INVISIBLE (-6505 2430);
FORCEPROP 1 LAST OFFPAGE TRUE
J 2
(-6875 2400);
DISPLAY 0.872340 (-6875 2400);
PAINT GREEN (-6875 2400);
DISPLAY INVISIBLE (-6875 2400);
FORCEPROP 2 LAST CDS_LIB standard
J 0
(-6550 2525);
DISPLAY INVISIBLE (-6550 2525);
FORCEADD OFFPAGE..2
R 2
(-6550 2475);
FORCEPROP 2 LAST $XR0 100 
J 0
(-6805 2475);
DISPLAY 0.638298 (-6805 2475);
PAINT MONO (-6805 2475);
FORCEPROP 2 LAST PATH I311
J 0
(-6800 2525);
DISPLAY 1.021277 (-6800 2525);
DISPLAY INVISIBLE (-6800 2525);
FORCEPROP 1 LAST COMMENT_BODY TRUE
J 2
(-6505 2380);
DISPLAY 0.872340 (-6505 2380);
PAINT GREEN (-6505 2380);
DISPLAY INVISIBLE (-6505 2380);
FORCEPROP 1 LAST OFFPAGE TRUE
J 2
(-6875 2350);
DISPLAY 0.872340 (-6875 2350);
PAINT GREEN (-6875 2350);
DISPLAY INVISIBLE (-6875 2350);
FORCEPROP 2 LAST CDS_LIB standard
J 0
(-6550 2475);
DISPLAY INVISIBLE (-6550 2475);
FORCEADD OFFPAGE..1
(-6550 2375);
FORCEPROP 2 LAST $XR0 100 
J 0
(-6832 2375);
DISPLAY 0.638298 (-6832 2375);
PAINT MONO (-6832 2375);
FORCEPROP 2 LAST PATH I312
J 0
(-6825 2425);
DISPLAY 1.021277 (-6825 2425);
DISPLAY INVISIBLE (-6825 2425);
FORCEPROP 1 LAST COMMENT_BODY TRUE
J 0
(-6425 2275);
DISPLAY 0.872340 (-6425 2275);
PAINT GREEN (-6425 2275);
DISPLAY INVISIBLE (-6425 2275);
FORCEPROP 1 LAST OFFPAGE TRUE
J 0
(-6225 2250);
DISPLAY 0.872340 (-6225 2250);
PAINT GREEN (-6225 2250);
DISPLAY INVISIBLE (-6225 2250);
FORCEPROP 2 LAST CDS_LIB standard
J 0
(-6550 2375);
DISPLAY INVISIBLE (-6550 2375);
FORCEADD OFFPAGE..5
(-6550 2275);
FORCEPROP 2 LAST $XR0 100 
J 0
(-6805 2275);
DISPLAY 0.638298 (-6805 2275);
PAINT MONO (-6805 2275);
FORCEPROP 2 LAST PATH I313
J 0
(-6800 2325);
DISPLAY 1.021277 (-6800 2325);
DISPLAY INVISIBLE (-6800 2325);
FORCEPROP 1 LAST COMMENT_BODY TRUE
J 0
(-6450 2200);
DISPLAY 0.872340 (-6450 2200);
PAINT GREEN (-6450 2200);
DISPLAY INVISIBLE (-6450 2200);
FORCEPROP 1 LAST OFFPAGE TRUE
J 0
(-6225 2150);
DISPLAY 0.872340 (-6225 2150);
PAINT GREEN (-6225 2150);
DISPLAY INVISIBLE (-6225 2150);
FORCEPROP 2 LAST CDS_LIB standard
J 0
(-6550 2275);
DISPLAY INVISIBLE (-6550 2275);
FORCEADD Q_RES..1
(-6625 2175);
FORCEPROP 1 LAST LOCATION R503
J 0
(-6950 2175);
DISPLAY 0.489362 (-6950 2175);
PAINT SKYBLUE (-6950 2175);
FORCEPROP 0 LAST $SEC 1
J 0
(-6800 2225);
DISPLAY 0.680851 (-6800 2225);
PAINT MONO (-6800 2225);
DISPLAY INVISIBLE (-6800 2225);
FORCEPROP 0 LAST CDS_SEC 1
J 0
(-6800 2225);
DISPLAY 1.021277 (-6800 2225);
DISPLAY INVISIBLE (-6800 2225);
FORCEPROP 1 LASTPIN (-6725 2175) $PN 1
J 0
(-6713 2187);
DISPLAY 0.489362 (-6713 2187);
PAINT MONO (-6713 2187);
FORCEPROP 1 LASTPIN (-6525 2175) $PN 2
J 0
(-6563 2187);
DISPLAY 0.489362 (-6563 2187);
PAINT MONO (-6563 2187);
FORCEPROP 1 LAST TOLERANCE 1%
J 0
(-6350 2175);
DISPLAY 0.489362 (-6350 2175);
PAINT SKYBLUE (-6350 2175);
FORCEPROP 1 LAST VALUE 15   
J 2
(-6300 2175);
DISPLAY 0.489362 (-6300 2175);
PAINT SKYBLUE (-6300 2175);
FORCEPROP 1 LAST PART_NUMBER CS01502FB11
J 0
(-6500 2150);
DISPLAY 0.489362 (-6500 2150);
PAINT SKYBLUE (-6500 2150);
FORCEPROP 1 LAST PACK_TYPE 0402LF
J 0
(-6950 2150);
DISPLAY 0.489362 (-6950 2150);
PAINT SKYBLUE (-6950 2150);
FORCEPROP 2 LAST CDS_LIB pure_quanta
J 0
(-6625 2175);
DISPLAY INVISIBLE (-6625 2175);
FORCEPROP 1 LAST PATH I314
J 0
(-6675 2325);
DISPLAY 0.978723 (-6675 2325);
PAINT WHITE (-6675 2325);
DISPLAY INVISIBLE (-6675 2325);
FORCEPROP 1 LAST WATTAGE 1/16W
J 2
(-6400 2300);
DISPLAY 0.638298 (-6400 2300);
PAINT SKYBLUE (-6400 2300);
DISPLAY INVISIBLE (-6400 2300);
FORCEPROP 1 LAST MATERIAL CHIP
J 0
(-6750 2300);
DISPLAY 0.638298 (-6750 2300);
PAINT SKYBLUE (-6750 2300);
DISPLAY INVISIBLE (-6750 2300);
FORCEADD OFFPAGE..1
(-7500 2175);
FORCEPROP 2 LAST $XR0 100 
J 0
(-7752 2175);
DISPLAY 0.638298 (-7752 2175);
PAINT MONO (-7752 2175);
FORCEPROP 2 LAST PATH I315
J 0
(-7750 2225);
DISPLAY 1.021277 (-7750 2225);
DISPLAY INVISIBLE (-7750 2225);
FORCEPROP 1 LAST COMMENT_BODY TRUE
J 0
(-7375 2075);
DISPLAY 0.872340 (-7375 2075);
PAINT GREEN (-7375 2075);
DISPLAY INVISIBLE (-7375 2075);
FORCEPROP 1 LAST OFFPAGE TRUE
J 0
(-7175 2050);
DISPLAY 0.872340 (-7175 2050);
PAINT GREEN (-7175 2050);
DISPLAY INVISIBLE (-7175 2050);
FORCEPROP 2 LAST CDS_LIB mstr_standard
J 0
(-7500 2175);
DISPLAY INVISIBLE (-7500 2175);
FORCEADD OFFPAGE..5
(-6550 2075);
FORCEPROP 2 LAST $XR0 100 
J 0
(-6805 2075);
DISPLAY 0.638298 (-6805 2075);
PAINT MONO (-6805 2075);
FORCEPROP 2 LAST PATH I316
J 0
(-6800 2125);
DISPLAY 1.021277 (-6800 2125);
DISPLAY INVISIBLE (-6800 2125);
FORCEPROP 1 LAST COMMENT_BODY TRUE
J 0
(-6450 2000);
DISPLAY 0.872340 (-6450 2000);
PAINT GREEN (-6450 2000);
DISPLAY INVISIBLE (-6450 2000);
FORCEPROP 1 LAST OFFPAGE TRUE
J 0
(-6225 1950);
DISPLAY 0.872340 (-6225 1950);
PAINT GREEN (-6225 1950);
DISPLAY INVISIBLE (-6225 1950);
FORCEPROP 2 LAST CDS_LIB standard
J 0
(-6550 2075);
DISPLAY INVISIBLE (-6550 2075);
FORCEADD CAD_NOTE..1
(-7725 2475);
FORCEPROP 0 LAST L1 R1961 PLACE CLOSE TO CPU < 25MM
J 0
(-7875 2350);
DISPLAY 0.617021 (-7875 2350);
PAINT WHITE (-7875 2350);
FORCEPROP 2 LAST CDS_LIB pure_quanta_power
J 0
(-7725 2475);
DISPLAY INVISIBLE (-7725 2475);
FORCEPROP 1 LAST COMMENT_BODY TRUE
J 0
(-7700 2575);
DISPLAY 0.574468 (-7700 2575);
PAINT WHITE (-7700 2575);
DISPLAY INVISIBLE (-7700 2575);
FORCEADD QUANTA_TITLE_BLOCK_C..1
(-100 100);
FORCEPROP 0 LAST CDS_CON_LAST_MODIFIED Fri Mar 11 14:52:30 2022
J 0
(-1985 115);
DISPLAY INVISIBLE (-1985 115);
FORCEPROP 1 LAST CUSTOM_TXT_CDS <CON_LAST_MODIFIED>
J 0
(-1985 115);
DISPLAY 0.978723 (-1985 115);
FORCEPROP 2 LAST CUSTOM_TXT_CDS <XR_PAGE_TITLE>
J 0
(-7990 5350);
DISPLAY 0.638298 (-7990 5350);
PAINT PINK (-7990 5350);
DISPLAY INVISIBLE (-7990 5350);
FORCEPROP 1 LAST CUSTOM_TXT_CDS <NAME_2>
J 0
(-3275 150);
FORCEPROP 1 LAST CUSTOM_TXT_CDS <NAME_1>
J 0
(-3275 275);
FORCEPROP 1 LAST CUSTOM_TXT_CDS <Q_NUMBER>
J 0
(-1503 203);
DISPLAY 1.212766 (-1503 203);
FORCEPROP 1 LAST CUSTOM_TXT_CDS <Q_PROJ>
J 0
(-2482 202);
DISPLAY 1.212766 (-2482 202);
FORCEPROP 1 LAST CUSTOM_TXT_CDS <Q_REV>
J 0
(-284 203);
DISPLAY 1.212766 (-284 203);
FORCEPROP 1 LAST CUSTOM_TXT_CDS <CON_PAGE_NUM> OF <CON_TOTAL_PAGES>
J 0
(-546 118);
DISPLAY 0.978723 (-546 118);
FORCEPROP 1 LAST Q_TITLE CPU1 DDR CHD
J 0
(-9400 150);
DISPLAY 2.446809 (-9400 150);
PAINT GREEN (-9400 150);
FORCEPROP 1 LAST Q_DEPT BU9
J 1
(-3863 149);
DISPLAY 1.957447 (-3863 149);
PAINT GREEN (-3863 149);
FORCEPROP 2 LAST PAGE_BORDER TRUE
J 0
(-7990 5350);
DISPLAY 0.638298 (-7990 5350);
PAINT PINK (-7990 5350);
DISPLAY INVISIBLE (-7990 5350);
FORCEPROP 2 LAST CDS_LIB pure_quanta
J 0
(-100 100);
DISPLAY INVISIBLE (-100 100);
FORCEPROP 1 LAST CDS_LMAN_SYM_OUTLINE -9475,6775,100,-125
J 0
(-100 100);
DISPLAY 0.468085 (-100 100);
PAINT GREEN (-100 100);
DISPLAY INVISIBLE (-100 100);
FORCEPROP 1 LAST COMMENT_BODY TRUE
J 0
(-88 87);
DISPLAY 0.978723 (-88 87);
PAINT GREEN (-88 87);
DISPLAY INVISIBLE (-88 87);
FORCEPROP 2 LAST CDS_XR_PAGE_TITLE CR-40 : @T6G_MB_LIB.T6G(SCH_1):PAGE40
J 0
(-7990 5350);
DISPLAY 0.638298 (-7990 5350);
PAINT PINK (-7990 5350);
DISPLAY INVISIBLE (-7990 5350);
WIRE 17 -1 (-3275 5900)(-3275 5850);
WIRE 17 -1 (-3275 5950)(-3275 5900);
WIRE 17 -1 (-3275 5850)(-3275 5800);
WIRE 17 -1 (-3275 5800)(-3275 5750);
WIRE 17 -1 (-3275 6000)(-3275 5950);
WIRE 17 -1 (-3275 6050)(-3275 6000);
WIRE 17 -1 (-3275 5750)(-3275 5700);
WIRE 17 -1 (-3275 5700)(-3275 5600);
WIRE 17 -1 (-3275 6050)(-2650 6050);
FORCEPROP 2 LAST SIG_NAME M_D_CPU1_SA_DQ<31:0>
J 2
(-2710 6060);
DISPLAY 0.489362 (-2710 6060);
WIRE 17 -1 (-3275 5600)(-3275 5550);
WIRE 17 -1 (-3275 5550)(-3275 5500);
WIRE 17 -1 (-3275 5500)(-3275 5450);
WIRE 17 -1 (-3275 5450)(-3275 5400);
WIRE 17 -1 (-3275 5400)(-3275 5350);
WIRE 17 -1 (-3275 5350)(-3275 5300);
WIRE 17 -1 (-3275 5300)(-3275 5250);
WIRE 17 -1 (-3275 5150)(-3275 5250);
WIRE 17 -1 (-3275 5100)(-3275 5150);
WIRE 17 -1 (-3275 5050)(-3275 5100);
WIRE 17 -1 (-3275 5000)(-3275 5050);
WIRE 17 -1 (-3275 5000)(-3275 4950);
WIRE 17 -1 (-3275 4950)(-3275 4900);
WIRE 17 -1 (-3275 4900)(-3275 4850);
WIRE 17 -1 (-3275 4850)(-3275 4800);
WIRE 17 -1 (-3275 4800)(-3275 4700);
WIRE 17 -1 (-3275 4700)(-3275 4650);
WIRE 17 -1 (-3275 4650)(-3275 4600);
WIRE 17 -1 (-3275 4600)(-3275 4550);
WIRE 17 -1 (-3275 4500)(-3275 4550);
WIRE 17 -1 (-3275 4450)(-3275 4500);
WIRE 17 -1 (-3275 4400)(-3275 4450);
WIRE 17 -1 (-3275 4350)(-3275 4400);
WIRE 17 -1 (-3275 4150)(-3275 4100);
WIRE 17 -1 (-3275 4200)(-3275 4150);
WIRE 17 -1 (-3275 4100)(-3275 4050);
WIRE 17 -1 (-3275 4050)(-3275 4000);
WIRE 17 -1 (-3275 4250)(-3275 4200);
WIRE 17 -1 (-3275 4250)(-2650 4250);
FORCEPROP 2 LAST SIG_NAME M_D_CPU1_SB_DQ<31:0>
J 2
(-2710 4260);
DISPLAY 0.489362 (-2710 4260);
WIRE 17 -1 (-3275 3600)(-3275 3550);
WIRE 17 -1 (-3275 3650)(-3275 3600);
WIRE 17 -1 (-3275 3550)(-3275 3500);
WIRE 17 -1 (-3275 3500)(-3275 3450);
WIRE 17 -1 (-3275 3700)(-3275 3650);
WIRE 17 -1 (-3275 3750)(-3275 3700);
WIRE 17 -1 (-3275 3350)(-3275 3450);
WIRE 17 -1 (-3275 3300)(-3275 3350);
WIRE 17 -1 (-3275 3800)(-3275 3750);
WIRE 17 -1 (-3275 3900)(-3275 3800);
WIRE 17 -1 (-3275 3250)(-3275 3300);
WIRE 17 -1 (-3275 3200)(-3275 3250);
WIRE 17 -1 (-3275 3950)(-3275 3900);
WIRE 17 -1 (-3275 4000)(-3275 3950);
WIRE 17 -1 (-3275 3200)(-3275 3150);
WIRE 17 -1 (-3275 3150)(-3275 3100);
WIRE 17 -1 (-3275 3100)(-3275 3050);
WIRE 17 -1 (-3275 3050)(-3275 3000);
WIRE 17 -1 (-3275 3000)(-3275 2900);
WIRE 17 -1 (-3275 2900)(-3275 2850);
WIRE 17 -1 (-3275 2850)(-3275 2800);
WIRE 17 -1 (-3275 2800)(-3275 2750);
WIRE 17 -1 (-3275 2700)(-3275 2750);
WIRE 17 -1 (-3275 2650)(-3275 2700);
WIRE 17 -1 (-3275 2600)(-3275 2650);
WIRE 17 -1 (-3275 2550)(-3275 2600);
WIRE 17 -1 (-3275 2450)(-3275 2400);
WIRE 17 -1 (-3275 2450)(-3275 2475);
WIRE 17 -1 (-3275 2350)(-3275 2400);
WIRE 17 -1 (-3275 2350)(-3275 2300);
WIRE 17 -1 (-3275 2475)(-2775 2475);
FORCEPROP 2 LAST SIG_NAME M_D_CPU1_SA_CB<7:0>
J 2
(-2775 2485);
DISPLAY 0.489362 (-2775 2485);
WIRE 17 -1 (-3275 2250)(-3275 2300);
WIRE 17 -1 (-3275 2200)(-3275 2250);
WIRE 17 -1 (-3275 2150)(-3275 2200);
WIRE 17 -1 (-3275 2100)(-3275 2150);
WIRE 17 -1 (-3275 1900)(-3275 1850);
WIRE 17 -1 (-3275 1900)(-3275 1950);
WIRE 17 -1 (-3275 1800)(-3275 1850);
WIRE 17 -1 (-3275 1750)(-3275 1800);
WIRE 17 -1 (-3275 2000)(-3275 1950);
WIRE 17 -1 (-3275 2000)(-3275 2025);
WIRE 17 -1 (-3275 1700)(-3275 1750);
WIRE 17 -1 (-3275 1650)(-3275 1700);
WIRE 17 -1 (-3275 2025)(-2775 2025);
FORCEPROP 2 LAST SIG_NAME M_D_CPU1_SB_CB<7:0>
J 2
(-2775 2035);
DISPLAY 0.489362 (-2775 2035);
WIRE 17 -1 (-6000 5500)(-6000 5600);
WIRE 17 -1 (-6000 5400)(-6000 5500);
WIRE 17 -1 (-6000 5700)(-6000 5600);
WIRE 17 -1 (-6000 5800)(-6000 5700);
WIRE 17 -1 (-6000 5300)(-6000 5400);
WIRE 17 -1 (-6000 5300)(-6000 5200);
WIRE 17 -1 (-6000 5900)(-6000 5800);
WIRE 17 -1 (-6000 6000)(-6000 5900);
FORCEPROP 2 LAST SIG_NAME M_D_CPU1_SA_DQS_DN<9:0>
J 2
(-6035 6010);
DISPLAY 0.489362 (-6035 6010);
WIRE 17 -1 (-5800 5950)(-5800 5850);
WIRE 17 -1 (-5800 6050)(-5800 5950);
WIRE 17 -1 (-5800 5850)(-5800 5750);
WIRE 17 -1 (-5800 5750)(-5800 5650);
WIRE 17 -1 (-5800 6050)(-6600 6050);
FORCEPROP 2 LAST SIG_NAME M_D_CPU1_SA_DQS_DP<9:0>
J 2
(-6035 6060);
DISPLAY 0.489362 (-6035 6060);
WIRE 17 -1 (-6000 5200)(-6000 5100);
WIRE 17 -1 (-5800 5550)(-5800 5650);
WIRE 17 -1 (-5800 5450)(-5800 5550);
WIRE 17 -1 (-5800 5350)(-5800 5450);
WIRE 17 -1 (-5800 5350)(-5800 5250);
WIRE 17 -1 (-5800 5250)(-5800 5150);
WIRE 17 -1 (-6000 4950)(-6000 4850);
FORCEPROP 2 LAST SIG_NAME M_D_CPU1_SB_DQS_DN<9:0>
J 2
(-6035 4960);
DISPLAY 0.489362 (-6035 4960);
WIRE 17 -1 (-6000 4750)(-6000 4650);
WIRE 17 -1 (-6000 4850)(-6000 4750);
WIRE 17 -1 (-6000 4650)(-6000 4550);
WIRE 17 -1 (-6000 4450)(-6000 4550);
WIRE 17 -1 (-6000 4350)(-6000 4450);
WIRE 17 -1 (-6000 4250)(-6000 4350);
WIRE 17 -1 (-6000 4250)(-6000 4150);
WIRE 17 -1 (-5800 5000)(-5800 4900);
WIRE 17 -1 (-5800 5000)(-6600 5000);
FORCEPROP 2 LAST SIG_NAME M_D_CPU1_SB_DQS_DP<9:0>
J 2
(-6035 5010);
DISPLAY 0.489362 (-6035 5010);
WIRE 17 -1 (-6000 4150)(-6000 4050);
WIRE 17 -1 (-5800 4900)(-5800 4800);
WIRE 17 -1 (-5800 4800)(-5800 4700);
WIRE 17 -1 (-5800 4700)(-5800 4600);
WIRE 17 -1 (-5800 4500)(-5800 4600);
WIRE 17 -1 (-5800 4400)(-5800 4500);
WIRE 17 -1 (-5800 4300)(-5800 4400);
WIRE 17 -1 (-5800 4300)(-5800 4200);
WIRE 17 -1 (-5800 4200)(-5800 4100);
WIRE 17 -1 (-6000 3850)(-6000 3900);
WIRE 17 -1 (-6000 3800)(-6000 3850);
WIRE 17 -1 (-6000 3900)(-6500 3900);
FORCEPROP 2 LAST SIG_NAME M_D_CPU1_SA_CA<6:0>
J 0
(-6500 3910);
DISPLAY 0.489362 (-6500 3910);
WIRE 17 -1 (-6000 3450)(-6000 3500);
WIRE 17 -1 (-6000 3400)(-6000 3450);
WIRE 17 -1 (-6000 3500)(-6500 3500);
FORCEPROP 2 LAST SIG_NAME M_D_CPU1_SB_CA<6:0>
J 0
(-6500 3510);
DISPLAY 0.489362 (-6500 3510);
WIRE 17 -1 (-6000 3750)(-6000 3800);
WIRE 17 -1 (-6000 3350)(-6000 3400);
WIRE 17 -1 (-6000 3700)(-6000 3750);
WIRE 17 -1 (-6000 3650)(-6000 3700);
WIRE 17 -1 (-6000 3600)(-6000 3650);
WIRE 17 -1 (-6000 3300)(-6000 3350);
WIRE 17 -1 (-6000 3250)(-6000 3300);
WIRE 17 -1 (-6000 3200)(-6000 3250);
WIRE 17 -1 (-6000 6000)(-6600 6000);
WIRE 17 -1 (-6000 4950)(-6600 4950);
WIRE 16 -1 (-7450 2175)(-6725 2175);
FORCEPROP 2 LAST SIG_NAME M_D_CPU1_ALERT_N
J 0
(-7410 2185);
DISPLAY 0.489362 (-7410 2185);
WIRE 16 -1 (-6500 1225)(-5400 1225);
FORCEPROP 2 LAST SIG_NAME TP_M_D_CPU1_SA_TEST39D
J 0
(-6485 1235);
DISPLAY 0.489362 (-6485 1235);
FORCEPROP 2 LASTPROP $XRERR UNIQUE?
J 0
(-6740 1225);
DISPLAY 0.638298 (-6740 1225);
PAINT MONO (-6740 1225);
DISPLAY INVISIBLE (-6740 1225);
WIRE 16 -1 (-6525 2175)(-5400 2175);
FORCEPROP 2 LAST SIG_NAME M_D_CPU1_ALERT_R_N
J 0
(-6235 2185);
DISPLAY 0.489362 (-6235 2185);
FORCEPROP 2 LASTPROP $XRERR UNIQUE?
J 0
(-6475 2185);
DISPLAY 0.638298 (-6475 2185);
PAINT MONO (-6475 2185);
DISPLAY INVISIBLE (-6475 2185);
WIRE 16 -1 (-6500 3025)(-5400 3025);
FORCEPROP 2 LAST SIG_NAME M_D_CPU1_CLK_DP<0>
J 0
(-6500 3035);
DISPLAY 0.489362 (-6500 3035);
WIRE 16 -1 (-6500 2975)(-5400 2975);
FORCEPROP 2 LAST SIG_NAME M_D_CPU1_CLK_DN<0>
J 0
(-6500 2985);
DISPLAY 0.489362 (-6500 2985);
WIRE 16 -1 (-6500 2875)(-5400 2875);
FORCEPROP 2 LAST SIG_NAME M_D_CPU1_SA_CS_N<0>
J 0
(-6500 2885);
DISPLAY 0.489362 (-6500 2885);
WIRE 16 -1 (-6500 2825)(-5400 2825);
FORCEPROP 2 LAST SIG_NAME M_D_CPU1_SA_CS_N<1>
J 0
(-6500 2835);
DISPLAY 0.489362 (-6500 2835);
WIRE 16 -1 (-6500 2725)(-5400 2725);
FORCEPROP 2 LAST SIG_NAME M_D_CPU1_SA_RSP<0>
J 0
(-6500 2735);
DISPLAY 0.489362 (-6500 2735);
WIRE 16 -1 (-6500 2625)(-5400 2625);
FORCEPROP 2 LAST SIG_NAME M_D_CPU1_SA_PAR
J 0
(-6500 2635);
DISPLAY 0.489362 (-6500 2635);
WIRE 16 -1 (-6500 2525)(-5400 2525);
FORCEPROP 2 LAST SIG_NAME M_D_CPU1_SB_CS_N<0>
J 0
(-6500 2535);
DISPLAY 0.489362 (-6500 2535);
WIRE 16 -1 (-6500 2475)(-5400 2475);
FORCEPROP 2 LAST SIG_NAME M_D_CPU1_SB_CS_N<1>
J 0
(-6500 2485);
DISPLAY 0.489362 (-6500 2485);
WIRE 16 -1 (-6500 2375)(-5400 2375);
FORCEPROP 2 LAST SIG_NAME M_D_CPU1_SB_RSP<0>
J 0
(-6500 2385);
DISPLAY 0.489362 (-6500 2385);
WIRE 16 -1 (-6500 2275)(-5400 2275);
FORCEPROP 2 LAST SIG_NAME M_D_CPU1_SB_PAR
J 0
(-6500 2285);
DISPLAY 0.489362 (-6500 2285);
WIRE 16 -1 (-6500 2075)(-5400 2075);
FORCEPROP 2 LAST SIG_NAME M_D_CPU1_RESET_N
J 0
(-6500 2085);
DISPLAY 0.489362 (-6500 2085);
WIRE 16 -1 (-5700 4075)(-5400 4075);
WIRE 16 -1 (-5900 3325)(-5400 3325);
WIRE 16 -1 (-5900 3175)(-5400 3175);
WIRE 16 -1 (-5900 3575)(-5400 3575);
WIRE 16 -1 (-5900 3225)(-5400 3225);
WIRE 16 -1 (-5900 3625)(-5400 3625);
WIRE 16 -1 (-5900 3275)(-5400 3275);
WIRE 16 -1 (-5900 3675)(-5400 3675);
WIRE 16 -1 (-5900 4025)(-5400 4025);
WIRE 16 -1 (-5900 3725)(-5400 3725);
WIRE 16 -1 (-5900 3375)(-5400 3375);
WIRE 16 -1 (-5900 3775)(-5400 3775);
WIRE 16 -1 (-5900 3425)(-5400 3425);
WIRE 16 -1 (-5900 3825)(-5400 3825);
WIRE 16 -1 (-5900 3475)(-5400 3475);
WIRE 16 -1 (-5900 3875)(-5400 3875);
WIRE 16 -1 (-5700 4175)(-5400 4175);
WIRE 16 -1 (-5700 4275)(-5400 4275);
WIRE 16 -1 (-5700 4375)(-5400 4375);
WIRE 16 -1 (-5700 4475)(-5400 4475);
WIRE 16 -1 (-5700 4575)(-5400 4575);
WIRE 16 -1 (-5900 4125)(-5400 4125);
WIRE 16 -1 (-5700 4675)(-5400 4675);
WIRE 16 -1 (-5900 4225)(-5400 4225);
WIRE 16 -1 (-5700 4775)(-5400 4775);
WIRE 16 -1 (-5900 4325)(-5400 4325);
WIRE 16 -1 (-5700 4875)(-5400 4875);
WIRE 16 -1 (-5900 4425)(-5400 4425);
WIRE 16 -1 (-5700 4975)(-5400 4975);
WIRE 16 -1 (-5900 4525)(-5400 4525);
WIRE 16 -1 (-5900 5075)(-5400 5075);
WIRE 16 -1 (-5900 4625)(-5400 4625);
WIRE 16 -1 (-5900 4725)(-5400 4725);
WIRE 16 -1 (-5900 4825)(-5400 4825);
WIRE 16 -1 (-5900 4925)(-5400 4925);
WIRE 16 -1 (-5700 6025)(-5400 6025);
WIRE 16 -1 (-5900 5575)(-5400 5575);
WIRE 16 -1 (-5900 5675)(-5400 5675);
WIRE 16 -1 (-5900 5775)(-5400 5775);
WIRE 16 -1 (-5900 5875)(-5400 5875);
WIRE 16 -1 (-5900 5975)(-5400 5975);
WIRE 16 -1 (-5700 5125)(-5400 5125);
WIRE 16 -1 (-5700 5225)(-5400 5225);
WIRE 16 -1 (-5700 5325)(-5400 5325);
WIRE 16 -1 (-5700 5425)(-5400 5425);
WIRE 16 -1 (-5700 5525)(-5400 5525);
WIRE 16 -1 (-5700 5625)(-5400 5625);
WIRE 16 -1 (-5900 5175)(-5400 5175);
WIRE 16 -1 (-5700 5725)(-5400 5725);
WIRE 16 -1 (-5900 5275)(-5400 5275);
WIRE 16 -1 (-5700 5825)(-5400 5825);
WIRE 16 -1 (-5900 5375)(-5400 5375);
WIRE 16 -1 (-5700 5925)(-5400 5925);
WIRE 16 -1 (-5900 5475)(-5400 5475);
WIRE 16 -1 (-3800 1875)(-3375 1875);
WIRE 16 -1 (-3800 1925)(-3375 1925);
WIRE 16 -1 (-3800 1975)(-3375 1975);
WIRE 16 -1 (-3800 1625)(-3375 1625);
WIRE 16 -1 (-3800 1675)(-3375 1675);
WIRE 16 -1 (-3800 1725)(-3375 1725);
WIRE 16 -1 (-3800 1775)(-3375 1775);
WIRE 16 -1 (-3800 1825)(-3375 1825);
WIRE 16 -1 (-3800 3025)(-3375 3025);
WIRE 16 -1 (-3800 2075)(-3375 2075);
WIRE 16 -1 (-3800 2125)(-3375 2125);
WIRE 16 -1 (-3800 2525)(-3375 2525);
WIRE 16 -1 (-3800 2175)(-3375 2175);
WIRE 16 -1 (-3800 2575)(-3375 2575);
WIRE 16 -1 (-3800 2225)(-3375 2225);
WIRE 16 -1 (-3800 2275)(-3375 2275);
WIRE 16 -1 (-3800 2325)(-3375 2325);
WIRE 16 -1 (-3800 2375)(-3375 2375);
WIRE 16 -1 (-3800 2425)(-3375 2425);
WIRE 16 -1 (-3800 2625)(-3375 2625);
WIRE 16 -1 (-3800 2675)(-3375 2675);
WIRE 16 -1 (-3800 2725)(-3375 2725);
WIRE 16 -1 (-3800 2775)(-3375 2775);
WIRE 16 -1 (-3800 2825)(-3375 2825);
WIRE 16 -1 (-3800 2875)(-3375 2875);
WIRE 16 -1 (-3800 2975)(-3375 2975);
WIRE 16 -1 (-3800 3625)(-3375 3625);
WIRE 16 -1 (-3800 3675)(-3375 3675);
WIRE 16 -1 (-3800 3075)(-3375 3075);
WIRE 16 -1 (-3800 3125)(-3375 3125);
WIRE 16 -1 (-3800 3725)(-3375 3725);
WIRE 16 -1 (-3800 3175)(-3375 3175);
WIRE 16 -1 (-3800 3775)(-3375 3775);
WIRE 16 -1 (-3800 3225)(-3375 3225);
WIRE 16 -1 (-3800 3875)(-3375 3875);
WIRE 16 -1 (-3800 3275)(-3375 3275);
WIRE 16 -1 (-3800 3925)(-3375 3925);
WIRE 16 -1 (-3800 3325)(-3375 3325);
WIRE 16 -1 (-3800 3975)(-3375 3975);
WIRE 16 -1 (-3800 3425)(-3375 3425);
WIRE 16 -1 (-3800 4025)(-3375 4025);
WIRE 16 -1 (-3800 3475)(-3375 3475);
WIRE 16 -1 (-3800 4075)(-3375 4075);
WIRE 16 -1 (-3800 3525)(-3375 3525);
WIRE 16 -1 (-3800 3575)(-3375 3575);
WIRE 16 -1 (-3800 5075)(-3375 5075);
WIRE 16 -1 (-3800 4475)(-3375 4475);
WIRE 16 -1 (-3800 4175)(-3375 4175);
WIRE 16 -1 (-3800 4525)(-3375 4525);
WIRE 16 -1 (-3800 4225)(-3375 4225);
WIRE 16 -1 (-3800 4575)(-3375 4575);
WIRE 16 -1 (-3800 4625)(-3375 4625);
WIRE 16 -1 (-3800 4675)(-3375 4675);
WIRE 16 -1 (-3800 4775)(-3375 4775);
WIRE 16 -1 (-3800 4825)(-3375 4825);
WIRE 16 -1 (-3800 4875)(-3375 4875);
WIRE 16 -1 (-3800 4925)(-3375 4925);
WIRE 16 -1 (-3800 4325)(-3375 4325);
WIRE 16 -1 (-3800 4375)(-3375 4375);
WIRE 16 -1 (-3800 4975)(-3375 4975);
WIRE 16 -1 (-3800 5025)(-3375 5025);
WIRE 16 -1 (-3800 4425)(-3375 4425);
WIRE 16 -1 (-3800 4125)(-3375 4125);
WIRE 16 -1 (-3800 5925)(-3375 5925);
WIRE 16 -1 (-3800 5975)(-3375 5975);
WIRE 16 -1 (-3800 5125)(-3375 5125);
WIRE 16 -1 (-3800 6025)(-3375 6025);
WIRE 16 -1 (-3800 5225)(-3375 5225);
WIRE 16 -1 (-3800 5275)(-3375 5275);
WIRE 16 -1 (-3800 5325)(-3375 5325);
WIRE 16 -1 (-3800 5375)(-3375 5375);
WIRE 16 -1 (-3800 5425)(-3375 5425);
WIRE 16 -1 (-3800 5475)(-3375 5475);
WIRE 16 -1 (-3800 5525)(-3375 5525);
WIRE 16 -1 (-3800 5575)(-3375 5575);
WIRE 16 -1 (-3800 5675)(-3375 5675);
WIRE 16 -1 (-3800 5725)(-3375 5725);
WIRE 16 -1 (-3800 5775)(-3375 5775);
WIRE 16 -1 (-3800 5825)(-3375 5825);
WIRE 16 -1 (-3800 5875)(-3375 5875);
QUIT
